FILE_TYPE = MACRO_DRAWING;
SET COLOR_WIRE YELLOW;
SET COLOR_PROP ORANGE;
SET COLOR_DOT WHITE;
SET COLOR_ARC YELLOW;
SET COLOR_BODY GREEN;
SET COLOR_NOTE PURPLE;
SET PROP_DISPLAY VALUE;
SET PAGE_NUMBER P100;
FORCEADD OFFPAGE..5
(-8400 2125);
FORCEPROP 2 LAST $XR0 40 
J 0
(-8654 2125);
DISPLAY 0.638298 (-8654 2125);
PAINT MONO (-8654 2125);
FORCEPROP 2 LAST PATH I1
J 0
(-8600 2175);
DISPLAY 1.021277 (-8600 2175);
DISPLAY INVISIBLE (-8600 2175);
FORCEPROP 1 LAST COMMENT_BODY TRUE
J 0
(-8300 2050);
DISPLAY 0.872340 (-8300 2050);
PAINT GREEN (-8300 2050);
DISPLAY INVISIBLE (-8300 2050);
FORCEPROP 1 LAST OFFPAGE TRUE
J 0
(-8075 2000);
DISPLAY 0.872340 (-8075 2000);
PAINT GREEN (-8075 2000);
DISPLAY INVISIBLE (-8075 2000);
FORCEPROP 2 LAST CDS_LIB mstr_standard
J 0
(-8400 2125);
DISPLAY 0.808511 (-8400 2125);
DISPLAY INVISIBLE (-8400 2125);
FORCEADD OFFPAGE..6
(-8400 3775);
FORCEPROP 2 LAST $XR0 40 
J 0
(-8649 3775);
DISPLAY 0.638298 (-8649 3775);
PAINT MONO (-8649 3775);
FORCEPROP 2 LAST PATH I10
J 0
(-8625 3825);
DISPLAY 1.021277 (-8625 3825);
DISPLAY INVISIBLE (-8625 3825);
FORCEPROP 1 LAST COMMENT_BODY TRUE
J 0
(-8300 3700);
DISPLAY 0.872340 (-8300 3700);
PAINT GREEN (-8300 3700);
DISPLAY INVISIBLE (-8300 3700);
FORCEPROP 1 LAST OFFPAGE TRUE
J 0
(-8075 3650);
DISPLAY 0.872340 (-8075 3650);
PAINT GREEN (-8075 3650);
DISPLAY INVISIBLE (-8075 3650);
FORCEPROP 2 LAST CDS_LIB mstr_standard
J 0
(-8400 3775);
DISPLAY 0.723404 (-8400 3775);
PAINT MONO (-8400 3775);
DISPLAY INVISIBLE (-8400 3775);
FORCEADD TAP..1
(-6100 4225);
FORCEPROP 3 LASTPIN (-6150 4225) SIG_NAME M_D_CPU1_SA_DQ<4>
J 0
(-6140 4235);
DISPLAY 0.659574 (-6140 4235);
PAINT MONO (-6140 4235);
DISPLAY INVISIBLE (-6140 4235);
FORCEPROP 1 LASTPIN (-6150 4225) BN 4
J 0
(-6162 4233);
DISPLAY 0.489362 (-6162 4233);
PAINT GREEN (-6162 4233);
FORCEPROP 2 LAST CDS_LIB mstr_standard
J 0
(-6100 4225);
DISPLAY 0.723404 (-6100 4225);
PAINT MONO (-6100 4225);
DISPLAY INVISIBLE (-6100 4225);
FORCEPROP 1 LAST BODY_TYPE PLUMBING
J 0
(-6100 4275);
DISPLAY 0.872340 (-6100 4275);
PAINT GREEN (-6100 4275);
DISPLAY INVISIBLE (-6100 4275);
FORCEPROP 1 LAST HDL_TAP TRUE
J 0
(-5775 4100);
DISPLAY 0.872340 (-5775 4100);
DISPLAY INVISIBLE (-5775 4100);
FORCEPROP 1 LAST PATH I107
J 0
(-6102 4225);
DISPLAY 0.872340 (-6102 4225);
PAINT GREEN (-6102 4225);
DISPLAY INVISIBLE (-6102 4225);
FORCEADD TAP..1
(-6100 4275);
FORCEPROP 3 LASTPIN (-6150 4275) SIG_NAME M_D_CPU1_SA_DQ<5>
J 0
(-6140 4285);
DISPLAY 0.659574 (-6140 4285);
PAINT MONO (-6140 4285);
DISPLAY INVISIBLE (-6140 4285);
FORCEPROP 1 LASTPIN (-6150 4275) BN 5
J 0
(-6162 4283);
DISPLAY 0.489362 (-6162 4283);
PAINT GREEN (-6162 4283);
FORCEPROP 2 LAST CDS_LIB mstr_standard
J 0
(-6100 4275);
DISPLAY 0.723404 (-6100 4275);
PAINT MONO (-6100 4275);
DISPLAY INVISIBLE (-6100 4275);
FORCEPROP 1 LAST BODY_TYPE PLUMBING
J 0
(-6100 4325);
DISPLAY 0.872340 (-6100 4325);
PAINT GREEN (-6100 4325);
DISPLAY INVISIBLE (-6100 4325);
FORCEPROP 1 LAST HDL_TAP TRUE
J 0
(-5775 4150);
DISPLAY 0.872340 (-5775 4150);
DISPLAY INVISIBLE (-5775 4150);
FORCEPROP 1 LAST PATH I108
J 0
(-6102 4275);
DISPLAY 0.872340 (-6102 4275);
PAINT GREEN (-6102 4275);
DISPLAY INVISIBLE (-6102 4275);
FORCEADD TAP..1
(-6100 4325);
FORCEPROP 3 LASTPIN (-6150 4325) SIG_NAME M_D_CPU1_SA_DQ<6>
J 0
(-6140 4335);
DISPLAY 0.659574 (-6140 4335);
PAINT MONO (-6140 4335);
DISPLAY INVISIBLE (-6140 4335);
FORCEPROP 1 LASTPIN (-6150 4325) BN 6
J 0
(-6162 4333);
DISPLAY 0.489362 (-6162 4333);
PAINT GREEN (-6162 4333);
FORCEPROP 2 LAST CDS_LIB mstr_standard
J 0
(-6100 4325);
DISPLAY 0.723404 (-6100 4325);
PAINT MONO (-6100 4325);
DISPLAY INVISIBLE (-6100 4325);
FORCEPROP 1 LAST BODY_TYPE PLUMBING
J 0
(-6100 4375);
DISPLAY 0.872340 (-6100 4375);
PAINT GREEN (-6100 4375);
DISPLAY INVISIBLE (-6100 4375);
FORCEPROP 1 LAST HDL_TAP TRUE
J 0
(-5775 4200);
DISPLAY 0.872340 (-5775 4200);
DISPLAY INVISIBLE (-5775 4200);
FORCEPROP 1 LAST PATH I109
J 0
(-6102 4325);
DISPLAY 0.872340 (-6102 4325);
PAINT GREEN (-6102 4325);
DISPLAY INVISIBLE (-6102 4325);
FORCEADD OFFPAGE..6
(-8400 4225);
FORCEPROP 2 LAST $XR0 40 
J 0
(-8649 4225);
DISPLAY 0.638298 (-8649 4225);
PAINT MONO (-8649 4225);
FORCEPROP 2 LAST PATH I11
J 0
(-8625 4275);
DISPLAY 1.021277 (-8625 4275);
DISPLAY INVISIBLE (-8625 4275);
FORCEPROP 1 LAST COMMENT_BODY TRUE
J 0
(-8300 4150);
DISPLAY 0.872340 (-8300 4150);
PAINT GREEN (-8300 4150);
DISPLAY INVISIBLE (-8300 4150);
FORCEPROP 1 LAST OFFPAGE TRUE
J 0
(-8075 4100);
DISPLAY 0.872340 (-8075 4100);
PAINT GREEN (-8075 4100);
DISPLAY INVISIBLE (-8075 4100);
FORCEPROP 2 LAST CDS_LIB mstr_standard
J 0
(-8400 4225);
DISPLAY 0.723404 (-8400 4225);
PAINT MONO (-8400 4225);
DISPLAY INVISIBLE (-8400 4225);
FORCEADD TAP..1
(-6100 4375);
FORCEPROP 3 LASTPIN (-6150 4375) SIG_NAME M_D_CPU1_SA_DQ<7>
J 0
(-6140 4385);
DISPLAY 0.659574 (-6140 4385);
PAINT MONO (-6140 4385);
DISPLAY INVISIBLE (-6140 4385);
FORCEPROP 1 LASTPIN (-6150 4375) BN 7
J 0
(-6162 4383);
DISPLAY 0.489362 (-6162 4383);
PAINT GREEN (-6162 4383);
FORCEPROP 2 LAST CDS_LIB mstr_standard
J 0
(-6100 4375);
DISPLAY 0.723404 (-6100 4375);
PAINT MONO (-6100 4375);
DISPLAY INVISIBLE (-6100 4375);
FORCEPROP 1 LAST BODY_TYPE PLUMBING
J 0
(-6100 4425);
DISPLAY 0.872340 (-6100 4425);
PAINT GREEN (-6100 4425);
DISPLAY INVISIBLE (-6100 4425);
FORCEPROP 1 LAST HDL_TAP TRUE
J 0
(-5775 4250);
DISPLAY 0.872340 (-5775 4250);
DISPLAY INVISIBLE (-5775 4250);
FORCEPROP 1 LAST PATH I110
J 0
(-6102 4375);
DISPLAY 0.872340 (-6102 4375);
PAINT GREEN (-6102 4375);
DISPLAY INVISIBLE (-6102 4375);
FORCEADD TAP..1
(-6100 4425);
FORCEPROP 3 LASTPIN (-6150 4425) SIG_NAME M_D_CPU1_SA_DQ<8>
J 0
(-6140 4435);
DISPLAY 0.659574 (-6140 4435);
PAINT MONO (-6140 4435);
DISPLAY INVISIBLE (-6140 4435);
FORCEPROP 1 LASTPIN (-6150 4425) BN 8
J 0
(-6162 4433);
DISPLAY 0.489362 (-6162 4433);
PAINT GREEN (-6162 4433);
FORCEPROP 2 LAST CDS_LIB mstr_standard
J 0
(-6100 4425);
DISPLAY 0.723404 (-6100 4425);
PAINT MONO (-6100 4425);
DISPLAY INVISIBLE (-6100 4425);
FORCEPROP 1 LAST BODY_TYPE PLUMBING
J 0
(-6100 4475);
DISPLAY 0.872340 (-6100 4475);
PAINT GREEN (-6100 4475);
DISPLAY INVISIBLE (-6100 4475);
FORCEPROP 1 LAST HDL_TAP TRUE
J 0
(-5775 4300);
DISPLAY 0.872340 (-5775 4300);
DISPLAY INVISIBLE (-5775 4300);
FORCEPROP 1 LAST PATH I111
J 0
(-6102 4425);
DISPLAY 0.872340 (-6102 4425);
PAINT GREEN (-6102 4425);
DISPLAY INVISIBLE (-6102 4425);
FORCEADD TAP..1
(-6100 4475);
FORCEPROP 3 LASTPIN (-6150 4475) SIG_NAME M_D_CPU1_SA_DQ<9>
J 0
(-6140 4485);
DISPLAY 0.659574 (-6140 4485);
PAINT MONO (-6140 4485);
DISPLAY INVISIBLE (-6140 4485);
FORCEPROP 1 LASTPIN (-6150 4475) BN 9
J 0
(-6162 4483);
DISPLAY 0.489362 (-6162 4483);
PAINT GREEN (-6162 4483);
FORCEPROP 2 LAST CDS_LIB mstr_standard
J 0
(-6100 4475);
DISPLAY 0.723404 (-6100 4475);
PAINT MONO (-6100 4475);
DISPLAY INVISIBLE (-6100 4475);
FORCEPROP 1 LAST BODY_TYPE PLUMBING
J 0
(-6100 4525);
DISPLAY 0.872340 (-6100 4525);
PAINT GREEN (-6100 4525);
DISPLAY INVISIBLE (-6100 4525);
FORCEPROP 1 LAST HDL_TAP TRUE
J 0
(-5775 4350);
DISPLAY 0.872340 (-5775 4350);
DISPLAY INVISIBLE (-5775 4350);
FORCEPROP 1 LAST PATH I112
J 0
(-6102 4475);
DISPLAY 0.872340 (-6102 4475);
PAINT GREEN (-6102 4475);
DISPLAY INVISIBLE (-6102 4475);
FORCEADD TAP..1
(-6100 4575);
FORCEPROP 3 LASTPIN (-6150 4575) SIG_NAME M_D_CPU1_SA_DQ<11>
J 0
(-6140 4585);
DISPLAY 0.659574 (-6140 4585);
PAINT MONO (-6140 4585);
DISPLAY INVISIBLE (-6140 4585);
FORCEPROP 1 LASTPIN (-6150 4575) BN 11
J 0
(-6162 4583);
DISPLAY 0.489362 (-6162 4583);
PAINT GREEN (-6162 4583);
FORCEPROP 2 LAST CDS_LIB mstr_standard
J 0
(-6100 4575);
DISPLAY 0.723404 (-6100 4575);
PAINT MONO (-6100 4575);
DISPLAY INVISIBLE (-6100 4575);
FORCEPROP 1 LAST BODY_TYPE PLUMBING
J 0
(-6100 4625);
DISPLAY 0.872340 (-6100 4625);
PAINT GREEN (-6100 4625);
DISPLAY INVISIBLE (-6100 4625);
FORCEPROP 1 LAST HDL_TAP TRUE
J 0
(-5775 4450);
DISPLAY 0.872340 (-5775 4450);
DISPLAY INVISIBLE (-5775 4450);
FORCEPROP 1 LAST PATH I113
J 0
(-6102 4575);
DISPLAY 0.872340 (-6102 4575);
PAINT GREEN (-6102 4575);
DISPLAY INVISIBLE (-6102 4575);
FORCEADD TAP..1
(-6100 4525);
FORCEPROP 3 LASTPIN (-6150 4525) SIG_NAME M_D_CPU1_SA_DQ<10>
J 0
(-6140 4535);
DISPLAY 0.659574 (-6140 4535);
PAINT MONO (-6140 4535);
DISPLAY INVISIBLE (-6140 4535);
FORCEPROP 1 LASTPIN (-6150 4525) BN 10
J 0
(-6162 4533);
DISPLAY 0.489362 (-6162 4533);
PAINT GREEN (-6162 4533);
FORCEPROP 2 LAST CDS_LIB mstr_standard
J 0
(-6100 4525);
DISPLAY 0.723404 (-6100 4525);
PAINT MONO (-6100 4525);
DISPLAY INVISIBLE (-6100 4525);
FORCEPROP 1 LAST BODY_TYPE PLUMBING
J 0
(-6100 4575);
DISPLAY 0.872340 (-6100 4575);
PAINT GREEN (-6100 4575);
DISPLAY INVISIBLE (-6100 4575);
FORCEPROP 1 LAST HDL_TAP TRUE
J 0
(-5775 4400);
DISPLAY 0.872340 (-5775 4400);
DISPLAY INVISIBLE (-5775 4400);
FORCEPROP 1 LAST PATH I114
J 0
(-6102 4525);
DISPLAY 0.872340 (-6102 4525);
PAINT GREEN (-6102 4525);
DISPLAY INVISIBLE (-6102 4525);
FORCEADD TAP..1
(-6100 4625);
FORCEPROP 3 LASTPIN (-6150 4625) SIG_NAME M_D_CPU1_SA_DQ<12>
J 0
(-6140 4635);
DISPLAY 0.659574 (-6140 4635);
PAINT MONO (-6140 4635);
DISPLAY INVISIBLE (-6140 4635);
FORCEPROP 1 LASTPIN (-6150 4625) BN 12
J 0
(-6162 4633);
DISPLAY 0.489362 (-6162 4633);
PAINT GREEN (-6162 4633);
FORCEPROP 2 LAST CDS_LIB mstr_standard
J 0
(-6100 4625);
DISPLAY 0.723404 (-6100 4625);
PAINT MONO (-6100 4625);
DISPLAY INVISIBLE (-6100 4625);
FORCEPROP 1 LAST BODY_TYPE PLUMBING
J 0
(-6100 4675);
DISPLAY 0.872340 (-6100 4675);
PAINT GREEN (-6100 4675);
DISPLAY INVISIBLE (-6100 4675);
FORCEPROP 1 LAST HDL_TAP TRUE
J 0
(-5775 4500);
DISPLAY 0.872340 (-5775 4500);
DISPLAY INVISIBLE (-5775 4500);
FORCEPROP 1 LAST PATH I115
J 0
(-6102 4625);
DISPLAY 0.872340 (-6102 4625);
PAINT GREEN (-6102 4625);
DISPLAY INVISIBLE (-6102 4625);
FORCEADD TAP..1
(-6100 4675);
FORCEPROP 3 LASTPIN (-6150 4675) SIG_NAME M_D_CPU1_SA_DQ<13>
J 0
(-6140 4685);
DISPLAY 0.659574 (-6140 4685);
PAINT MONO (-6140 4685);
DISPLAY INVISIBLE (-6140 4685);
FORCEPROP 1 LASTPIN (-6150 4675) BN 13
J 0
(-6162 4683);
DISPLAY 0.489362 (-6162 4683);
PAINT GREEN (-6162 4683);
FORCEPROP 2 LAST CDS_LIB mstr_standard
J 0
(-6100 4675);
DISPLAY 0.723404 (-6100 4675);
PAINT MONO (-6100 4675);
DISPLAY INVISIBLE (-6100 4675);
FORCEPROP 1 LAST BODY_TYPE PLUMBING
J 0
(-6100 4725);
DISPLAY 0.872340 (-6100 4725);
PAINT GREEN (-6100 4725);
DISPLAY INVISIBLE (-6100 4725);
FORCEPROP 1 LAST HDL_TAP TRUE
J 0
(-5775 4550);
DISPLAY 0.872340 (-5775 4550);
DISPLAY INVISIBLE (-5775 4550);
FORCEPROP 1 LAST PATH I116
J 0
(-6102 4675);
DISPLAY 0.872340 (-6102 4675);
PAINT GREEN (-6102 4675);
DISPLAY INVISIBLE (-6102 4675);
FORCEADD TAP..1
(-6100 4725);
FORCEPROP 3 LASTPIN (-6150 4725) SIG_NAME M_D_CPU1_SA_DQ<14>
J 0
(-6140 4735);
DISPLAY 0.659574 (-6140 4735);
PAINT MONO (-6140 4735);
DISPLAY INVISIBLE (-6140 4735);
FORCEPROP 1 LASTPIN (-6150 4725) BN 14
J 0
(-6162 4733);
DISPLAY 0.489362 (-6162 4733);
PAINT GREEN (-6162 4733);
FORCEPROP 2 LAST CDS_LIB mstr_standard
J 0
(-6100 4725);
DISPLAY 0.723404 (-6100 4725);
PAINT MONO (-6100 4725);
DISPLAY INVISIBLE (-6100 4725);
FORCEPROP 1 LAST BODY_TYPE PLUMBING
J 0
(-6100 4775);
DISPLAY 0.872340 (-6100 4775);
PAINT GREEN (-6100 4775);
DISPLAY INVISIBLE (-6100 4775);
FORCEPROP 1 LAST HDL_TAP TRUE
J 0
(-5775 4600);
DISPLAY 0.872340 (-5775 4600);
DISPLAY INVISIBLE (-5775 4600);
FORCEPROP 1 LAST PATH I117
J 0
(-6102 4725);
DISPLAY 0.872340 (-6102 4725);
PAINT GREEN (-6102 4725);
DISPLAY INVISIBLE (-6102 4725);
FORCEADD TAP..1
(-6100 4825);
FORCEPROP 3 LASTPIN (-6150 4825) SIG_NAME M_D_CPU1_SA_DQ<16>
J 0
(-6140 4835);
DISPLAY 0.659574 (-6140 4835);
PAINT MONO (-6140 4835);
DISPLAY INVISIBLE (-6140 4835);
FORCEPROP 1 LASTPIN (-6150 4825) BN 16
J 0
(-6162 4833);
DISPLAY 0.489362 (-6162 4833);
PAINT GREEN (-6162 4833);
FORCEPROP 2 LAST CDS_LIB mstr_standard
J 0
(-6100 4825);
DISPLAY 0.723404 (-6100 4825);
PAINT MONO (-6100 4825);
DISPLAY INVISIBLE (-6100 4825);
FORCEPROP 1 LAST BODY_TYPE PLUMBING
J 0
(-6100 4875);
DISPLAY 0.872340 (-6100 4875);
PAINT GREEN (-6100 4875);
DISPLAY INVISIBLE (-6100 4875);
FORCEPROP 1 LAST HDL_TAP TRUE
J 0
(-5775 4700);
DISPLAY 0.872340 (-5775 4700);
DISPLAY INVISIBLE (-5775 4700);
FORCEPROP 1 LAST PATH I118
J 0
(-6102 4825);
DISPLAY 0.872340 (-6102 4825);
PAINT GREEN (-6102 4825);
DISPLAY INVISIBLE (-6102 4825);
FORCEADD TAP..1
(-6100 4775);
FORCEPROP 3 LASTPIN (-6150 4775) SIG_NAME M_D_CPU1_SA_DQ<15>
J 0
(-6140 4785);
DISPLAY 0.659574 (-6140 4785);
PAINT MONO (-6140 4785);
DISPLAY INVISIBLE (-6140 4785);
FORCEPROP 1 LASTPIN (-6150 4775) BN 15
J 0
(-6162 4783);
DISPLAY 0.489362 (-6162 4783);
PAINT GREEN (-6162 4783);
FORCEPROP 2 LAST CDS_LIB mstr_standard
J 0
(-6100 4775);
DISPLAY 0.723404 (-6100 4775);
PAINT MONO (-6100 4775);
DISPLAY INVISIBLE (-6100 4775);
FORCEPROP 1 LAST BODY_TYPE PLUMBING
J 0
(-6100 4825);
DISPLAY 0.872340 (-6100 4825);
PAINT GREEN (-6100 4825);
DISPLAY INVISIBLE (-6100 4825);
FORCEPROP 1 LAST HDL_TAP TRUE
J 0
(-5775 4650);
DISPLAY 0.872340 (-5775 4650);
DISPLAY INVISIBLE (-5775 4650);
FORCEPROP 1 LAST PATH I119
J 0
(-6102 4775);
DISPLAY 0.872340 (-6102 4775);
PAINT GREEN (-6102 4775);
DISPLAY INVISIBLE (-6102 4775);
FORCEADD TAP..1
R 2
(-7800 3425);
FORCEPROP 3 LASTPIN (-7750 3425) SIG_NAME M_D_CPU1_SB_CB<1>
J 0
(-7740 3435);
DISPLAY 0.659574 (-7740 3435);
PAINT MONO (-7740 3435);
DISPLAY INVISIBLE (-7740 3435);
FORCEPROP 1 LASTPIN (-7750 3425) BN 1
J 2
(-7738 3433);
DISPLAY 0.489362 (-7738 3433);
PAINT GREEN (-7738 3433);
FORCEPROP 2 LAST CDS_LIB mstr_standard
J 0
(-7800 3425);
DISPLAY 0.723404 (-7800 3425);
PAINT MONO (-7800 3425);
DISPLAY INVISIBLE (-7800 3425);
FORCEPROP 1 LAST BODY_TYPE PLUMBING
J 2
(-7800 3475);
DISPLAY 0.872340 (-7800 3475);
PAINT GREEN (-7800 3475);
DISPLAY INVISIBLE (-7800 3475);
FORCEPROP 1 LAST HDL_TAP TRUE
J 2
(-8125 3300);
DISPLAY 0.872340 (-8125 3300);
DISPLAY INVISIBLE (-8125 3300);
FORCEPROP 1 LAST PATH I12
J 2
(-7798 3425);
DISPLAY 0.872340 (-7798 3425);
PAINT GREEN (-7798 3425);
DISPLAY INVISIBLE (-7798 3425);
FORCEADD TAP..1
(-6100 4875);
FORCEPROP 3 LASTPIN (-6150 4875) SIG_NAME M_D_CPU1_SA_DQ<17>
J 0
(-6140 4885);
DISPLAY 0.659574 (-6140 4885);
PAINT MONO (-6140 4885);
DISPLAY INVISIBLE (-6140 4885);
FORCEPROP 1 LASTPIN (-6150 4875) BN 17
J 0
(-6162 4883);
DISPLAY 0.489362 (-6162 4883);
PAINT GREEN (-6162 4883);
FORCEPROP 2 LAST CDS_LIB mstr_standard
J 0
(-6100 4875);
DISPLAY 0.723404 (-6100 4875);
PAINT MONO (-6100 4875);
DISPLAY INVISIBLE (-6100 4875);
FORCEPROP 1 LAST BODY_TYPE PLUMBING
J 0
(-6100 4925);
DISPLAY 0.872340 (-6100 4925);
PAINT GREEN (-6100 4925);
DISPLAY INVISIBLE (-6100 4925);
FORCEPROP 1 LAST HDL_TAP TRUE
J 0
(-5775 4750);
DISPLAY 0.872340 (-5775 4750);
DISPLAY INVISIBLE (-5775 4750);
FORCEPROP 1 LAST PATH I120
J 0
(-6102 4875);
DISPLAY 0.872340 (-6102 4875);
PAINT GREEN (-6102 4875);
DISPLAY INVISIBLE (-6102 4875);
FORCEADD TAP..1
(-6100 4925);
FORCEPROP 3 LASTPIN (-6150 4925) SIG_NAME M_D_CPU1_SA_DQ<18>
J 0
(-6140 4935);
DISPLAY 0.659574 (-6140 4935);
PAINT MONO (-6140 4935);
DISPLAY INVISIBLE (-6140 4935);
FORCEPROP 1 LASTPIN (-6150 4925) BN 18
J 0
(-6162 4933);
DISPLAY 0.489362 (-6162 4933);
PAINT GREEN (-6162 4933);
FORCEPROP 2 LAST CDS_LIB mstr_standard
J 0
(-6100 4925);
DISPLAY 0.723404 (-6100 4925);
PAINT MONO (-6100 4925);
DISPLAY INVISIBLE (-6100 4925);
FORCEPROP 1 LAST BODY_TYPE PLUMBING
J 0
(-6100 4975);
DISPLAY 0.872340 (-6100 4975);
PAINT GREEN (-6100 4975);
DISPLAY INVISIBLE (-6100 4975);
FORCEPROP 1 LAST HDL_TAP TRUE
J 0
(-5775 4800);
DISPLAY 0.872340 (-5775 4800);
DISPLAY INVISIBLE (-5775 4800);
FORCEPROP 1 LAST PATH I121
J 0
(-6102 4925);
DISPLAY 0.872340 (-6102 4925);
PAINT GREEN (-6102 4925);
DISPLAY INVISIBLE (-6102 4925);
FORCEADD TAP..1
(-6100 5025);
FORCEPROP 3 LASTPIN (-6150 5025) SIG_NAME M_D_CPU1_SA_DQ<20>
J 0
(-6140 5035);
DISPLAY 0.659574 (-6140 5035);
PAINT MONO (-6140 5035);
DISPLAY INVISIBLE (-6140 5035);
FORCEPROP 1 LASTPIN (-6150 5025) BN 20
J 0
(-6162 5033);
DISPLAY 0.489362 (-6162 5033);
PAINT GREEN (-6162 5033);
FORCEPROP 2 LAST CDS_LIB mstr_standard
J 0
(-6100 5025);
DISPLAY 0.723404 (-6100 5025);
PAINT MONO (-6100 5025);
DISPLAY INVISIBLE (-6100 5025);
FORCEPROP 1 LAST BODY_TYPE PLUMBING
J 0
(-6100 5075);
DISPLAY 0.872340 (-6100 5075);
PAINT GREEN (-6100 5075);
DISPLAY INVISIBLE (-6100 5075);
FORCEPROP 1 LAST HDL_TAP TRUE
J 0
(-5775 4900);
DISPLAY 0.872340 (-5775 4900);
DISPLAY INVISIBLE (-5775 4900);
FORCEPROP 1 LAST PATH I122
J 0
(-6102 5025);
DISPLAY 0.872340 (-6102 5025);
PAINT GREEN (-6102 5025);
DISPLAY INVISIBLE (-6102 5025);
FORCEADD TAP..1
(-6100 4975);
FORCEPROP 3 LASTPIN (-6150 4975) SIG_NAME M_D_CPU1_SA_DQ<19>
J 0
(-6140 4985);
DISPLAY 0.659574 (-6140 4985);
PAINT MONO (-6140 4985);
DISPLAY INVISIBLE (-6140 4985);
FORCEPROP 1 LASTPIN (-6150 4975) BN 19
J 0
(-6162 4983);
DISPLAY 0.489362 (-6162 4983);
PAINT GREEN (-6162 4983);
FORCEPROP 2 LAST CDS_LIB mstr_standard
J 0
(-6100 4975);
DISPLAY 0.723404 (-6100 4975);
PAINT MONO (-6100 4975);
DISPLAY INVISIBLE (-6100 4975);
FORCEPROP 1 LAST BODY_TYPE PLUMBING
J 0
(-6100 5025);
DISPLAY 0.872340 (-6100 5025);
PAINT GREEN (-6100 5025);
DISPLAY INVISIBLE (-6100 5025);
FORCEPROP 1 LAST HDL_TAP TRUE
J 0
(-5775 4850);
DISPLAY 0.872340 (-5775 4850);
DISPLAY INVISIBLE (-5775 4850);
FORCEPROP 1 LAST PATH I123
J 0
(-6102 4975);
DISPLAY 0.872340 (-6102 4975);
PAINT GREEN (-6102 4975);
DISPLAY INVISIBLE (-6102 4975);
FORCEADD TAP..1
(-6100 5075);
FORCEPROP 3 LASTPIN (-6150 5075) SIG_NAME M_D_CPU1_SA_DQ<21>
J 0
(-6140 5085);
DISPLAY 0.659574 (-6140 5085);
PAINT MONO (-6140 5085);
DISPLAY INVISIBLE (-6140 5085);
FORCEPROP 1 LASTPIN (-6150 5075) BN 21
J 0
(-6162 5083);
DISPLAY 0.489362 (-6162 5083);
PAINT GREEN (-6162 5083);
FORCEPROP 2 LAST CDS_LIB mstr_standard
J 0
(-6100 5075);
DISPLAY 0.723404 (-6100 5075);
PAINT MONO (-6100 5075);
DISPLAY INVISIBLE (-6100 5075);
FORCEPROP 1 LAST BODY_TYPE PLUMBING
J 0
(-6100 5125);
DISPLAY 0.872340 (-6100 5125);
PAINT GREEN (-6100 5125);
DISPLAY INVISIBLE (-6100 5125);
FORCEPROP 1 LAST HDL_TAP TRUE
J 0
(-5775 4950);
DISPLAY 0.872340 (-5775 4950);
DISPLAY INVISIBLE (-5775 4950);
FORCEPROP 1 LAST PATH I124
J 0
(-6102 5075);
DISPLAY 0.872340 (-6102 5075);
PAINT GREEN (-6102 5075);
DISPLAY INVISIBLE (-6102 5075);
FORCEADD TAP..1
(-6100 5125);
FORCEPROP 3 LASTPIN (-6150 5125) SIG_NAME M_D_CPU1_SA_DQ<22>
J 0
(-6140 5135);
DISPLAY 0.659574 (-6140 5135);
PAINT MONO (-6140 5135);
DISPLAY INVISIBLE (-6140 5135);
FORCEPROP 1 LASTPIN (-6150 5125) BN 22
J 0
(-6162 5133);
DISPLAY 0.489362 (-6162 5133);
PAINT GREEN (-6162 5133);
FORCEPROP 2 LAST CDS_LIB mstr_standard
J 0
(-6100 5125);
DISPLAY 0.723404 (-6100 5125);
PAINT MONO (-6100 5125);
DISPLAY INVISIBLE (-6100 5125);
FORCEPROP 1 LAST BODY_TYPE PLUMBING
J 0
(-6100 5175);
DISPLAY 0.872340 (-6100 5175);
PAINT GREEN (-6100 5175);
DISPLAY INVISIBLE (-6100 5175);
FORCEPROP 1 LAST HDL_TAP TRUE
J 0
(-5775 5000);
DISPLAY 0.872340 (-5775 5000);
DISPLAY INVISIBLE (-5775 5000);
FORCEPROP 1 LAST PATH I125
J 0
(-6102 5125);
DISPLAY 0.872340 (-6102 5125);
PAINT GREEN (-6102 5125);
DISPLAY INVISIBLE (-6102 5125);
FORCEADD TAP..1
(-6100 5175);
FORCEPROP 3 LASTPIN (-6150 5175) SIG_NAME M_D_CPU1_SA_DQ<23>
J 0
(-6140 5185);
DISPLAY 0.659574 (-6140 5185);
PAINT MONO (-6140 5185);
DISPLAY INVISIBLE (-6140 5185);
FORCEPROP 1 LASTPIN (-6150 5175) BN 23
J 0
(-6162 5183);
DISPLAY 0.489362 (-6162 5183);
PAINT GREEN (-6162 5183);
FORCEPROP 2 LAST CDS_LIB mstr_standard
J 0
(-6100 5175);
DISPLAY 0.723404 (-6100 5175);
PAINT MONO (-6100 5175);
DISPLAY INVISIBLE (-6100 5175);
FORCEPROP 1 LAST BODY_TYPE PLUMBING
J 0
(-6100 5225);
DISPLAY 0.872340 (-6100 5225);
PAINT GREEN (-6100 5225);
DISPLAY INVISIBLE (-6100 5225);
FORCEPROP 1 LAST HDL_TAP TRUE
J 0
(-5775 5050);
DISPLAY 0.872340 (-5775 5050);
DISPLAY INVISIBLE (-5775 5050);
FORCEPROP 1 LAST PATH I126
J 0
(-6102 5175);
DISPLAY 0.872340 (-6102 5175);
PAINT GREEN (-6102 5175);
DISPLAY INVISIBLE (-6102 5175);
FORCEADD TAP..1
(-6100 5275);
FORCEPROP 3 LASTPIN (-6150 5275) SIG_NAME M_D_CPU1_SA_DQ<25>
J 0
(-6140 5285);
DISPLAY 0.659574 (-6140 5285);
PAINT MONO (-6140 5285);
DISPLAY INVISIBLE (-6140 5285);
FORCEPROP 1 LASTPIN (-6150 5275) BN 25
J 0
(-6162 5283);
DISPLAY 0.489362 (-6162 5283);
PAINT GREEN (-6162 5283);
FORCEPROP 2 LAST CDS_LIB mstr_standard
J 0
(-6100 5275);
DISPLAY 0.723404 (-6100 5275);
PAINT MONO (-6100 5275);
DISPLAY INVISIBLE (-6100 5275);
FORCEPROP 1 LAST BODY_TYPE PLUMBING
J 0
(-6100 5325);
DISPLAY 0.872340 (-6100 5325);
PAINT GREEN (-6100 5325);
DISPLAY INVISIBLE (-6100 5325);
FORCEPROP 1 LAST HDL_TAP TRUE
J 0
(-5775 5150);
DISPLAY 0.872340 (-5775 5150);
DISPLAY INVISIBLE (-5775 5150);
FORCEPROP 1 LAST PATH I127
J 0
(-6102 5275);
DISPLAY 0.872340 (-6102 5275);
PAINT GREEN (-6102 5275);
DISPLAY INVISIBLE (-6102 5275);
FORCEADD TAP..1
(-6100 5225);
FORCEPROP 3 LASTPIN (-6150 5225) SIG_NAME M_D_CPU1_SA_DQ<24>
J 0
(-6140 5235);
DISPLAY 0.659574 (-6140 5235);
PAINT MONO (-6140 5235);
DISPLAY INVISIBLE (-6140 5235);
FORCEPROP 1 LASTPIN (-6150 5225) BN 24
J 0
(-6162 5233);
DISPLAY 0.489362 (-6162 5233);
PAINT GREEN (-6162 5233);
FORCEPROP 2 LAST CDS_LIB mstr_standard
J 0
(-6100 5225);
DISPLAY 0.723404 (-6100 5225);
PAINT MONO (-6100 5225);
DISPLAY INVISIBLE (-6100 5225);
FORCEPROP 1 LAST BODY_TYPE PLUMBING
J 0
(-6100 5275);
DISPLAY 0.872340 (-6100 5275);
PAINT GREEN (-6100 5275);
DISPLAY INVISIBLE (-6100 5275);
FORCEPROP 1 LAST HDL_TAP TRUE
J 0
(-5775 5100);
DISPLAY 0.872340 (-5775 5100);
DISPLAY INVISIBLE (-5775 5100);
FORCEPROP 1 LAST PATH I128
J 0
(-6102 5225);
DISPLAY 0.872340 (-6102 5225);
PAINT GREEN (-6102 5225);
DISPLAY INVISIBLE (-6102 5225);
FORCEADD TAP..1
(-6100 5325);
FORCEPROP 3 LASTPIN (-6150 5325) SIG_NAME M_D_CPU1_SA_DQ<26>
J 0
(-6140 5335);
DISPLAY 0.659574 (-6140 5335);
PAINT MONO (-6140 5335);
DISPLAY INVISIBLE (-6140 5335);
FORCEPROP 1 LASTPIN (-6150 5325) BN 26
J 0
(-6162 5333);
DISPLAY 0.489362 (-6162 5333);
PAINT GREEN (-6162 5333);
FORCEPROP 2 LAST CDS_LIB mstr_standard
J 0
(-6100 5325);
DISPLAY 0.723404 (-6100 5325);
PAINT MONO (-6100 5325);
DISPLAY INVISIBLE (-6100 5325);
FORCEPROP 1 LAST BODY_TYPE PLUMBING
J 0
(-6100 5375);
DISPLAY 0.872340 (-6100 5375);
PAINT GREEN (-6100 5375);
DISPLAY INVISIBLE (-6100 5375);
FORCEPROP 1 LAST HDL_TAP TRUE
J 0
(-5775 5200);
DISPLAY 0.872340 (-5775 5200);
DISPLAY INVISIBLE (-5775 5200);
FORCEPROP 1 LAST PATH I129
J 0
(-6102 5325);
DISPLAY 0.872340 (-6102 5325);
PAINT GREEN (-6102 5325);
DISPLAY INVISIBLE (-6102 5325);
FORCEADD TAP..1
R 2
(-7800 3375);
FORCEPROP 3 LASTPIN (-7750 3375) SIG_NAME M_D_CPU1_SB_CB<0>
J 0
(-7740 3385);
DISPLAY 0.659574 (-7740 3385);
PAINT MONO (-7740 3385);
DISPLAY INVISIBLE (-7740 3385);
FORCEPROP 1 LASTPIN (-7750 3375) BN 0
J 2
(-7738 3383);
DISPLAY 0.489362 (-7738 3383);
PAINT GREEN (-7738 3383);
FORCEPROP 2 LAST CDS_LIB mstr_standard
J 0
(-7800 3375);
DISPLAY 0.723404 (-7800 3375);
PAINT MONO (-7800 3375);
DISPLAY INVISIBLE (-7800 3375);
FORCEPROP 1 LAST BODY_TYPE PLUMBING
J 2
(-7800 3425);
DISPLAY 0.872340 (-7800 3425);
PAINT GREEN (-7800 3425);
DISPLAY INVISIBLE (-7800 3425);
FORCEPROP 1 LAST HDL_TAP TRUE
J 2
(-8125 3250);
DISPLAY 0.872340 (-8125 3250);
DISPLAY INVISIBLE (-8125 3250);
FORCEPROP 1 LAST PATH I13
J 2
(-7798 3375);
DISPLAY 0.872340 (-7798 3375);
PAINT GREEN (-7798 3375);
DISPLAY INVISIBLE (-7798 3375);
FORCEADD TAP..1
(-6100 5375);
FORCEPROP 3 LASTPIN (-6150 5375) SIG_NAME M_D_CPU1_SA_DQ<27>
J 0
(-6140 5385);
DISPLAY 0.659574 (-6140 5385);
PAINT MONO (-6140 5385);
DISPLAY INVISIBLE (-6140 5385);
FORCEPROP 1 LASTPIN (-6150 5375) BN 27
J 0
(-6162 5383);
DISPLAY 0.489362 (-6162 5383);
PAINT GREEN (-6162 5383);
FORCEPROP 2 LAST CDS_LIB mstr_standard
J 0
(-6100 5375);
DISPLAY 0.723404 (-6100 5375);
PAINT MONO (-6100 5375);
DISPLAY INVISIBLE (-6100 5375);
FORCEPROP 1 LAST BODY_TYPE PLUMBING
J 0
(-6100 5425);
DISPLAY 0.872340 (-6100 5425);
PAINT GREEN (-6100 5425);
DISPLAY INVISIBLE (-6100 5425);
FORCEPROP 1 LAST HDL_TAP TRUE
J 0
(-5775 5250);
DISPLAY 0.872340 (-5775 5250);
DISPLAY INVISIBLE (-5775 5250);
FORCEPROP 1 LAST PATH I130
J 0
(-6102 5375);
DISPLAY 0.872340 (-6102 5375);
PAINT GREEN (-6102 5375);
DISPLAY INVISIBLE (-6102 5375);
FORCEADD TAP..1
(-6100 5475);
FORCEPROP 3 LASTPIN (-6150 5475) SIG_NAME M_D_CPU1_SA_DQ<29>
J 0
(-6140 5485);
DISPLAY 0.659574 (-6140 5485);
PAINT MONO (-6140 5485);
DISPLAY INVISIBLE (-6140 5485);
FORCEPROP 1 LASTPIN (-6150 5475) BN 29
J 0
(-6162 5483);
DISPLAY 0.489362 (-6162 5483);
PAINT GREEN (-6162 5483);
FORCEPROP 2 LAST CDS_LIB mstr_standard
J 0
(-6100 5475);
DISPLAY 0.723404 (-6100 5475);
PAINT MONO (-6100 5475);
DISPLAY INVISIBLE (-6100 5475);
FORCEPROP 1 LAST BODY_TYPE PLUMBING
J 0
(-6100 5525);
DISPLAY 0.872340 (-6100 5525);
PAINT GREEN (-6100 5525);
DISPLAY INVISIBLE (-6100 5525);
FORCEPROP 1 LAST HDL_TAP TRUE
J 0
(-5775 5350);
DISPLAY 0.872340 (-5775 5350);
DISPLAY INVISIBLE (-5775 5350);
FORCEPROP 1 LAST PATH I131
J 0
(-6102 5475);
DISPLAY 0.872340 (-6102 5475);
PAINT GREEN (-6102 5475);
DISPLAY INVISIBLE (-6102 5475);
FORCEADD TAP..1
(-6100 5425);
FORCEPROP 3 LASTPIN (-6150 5425) SIG_NAME M_D_CPU1_SA_DQ<28>
J 0
(-6140 5435);
DISPLAY 0.659574 (-6140 5435);
PAINT MONO (-6140 5435);
DISPLAY INVISIBLE (-6140 5435);
FORCEPROP 1 LASTPIN (-6150 5425) BN 28
J 0
(-6162 5433);
DISPLAY 0.489362 (-6162 5433);
PAINT GREEN (-6162 5433);
FORCEPROP 2 LAST CDS_LIB mstr_standard
J 0
(-6100 5425);
DISPLAY 0.723404 (-6100 5425);
PAINT MONO (-6100 5425);
DISPLAY INVISIBLE (-6100 5425);
FORCEPROP 1 LAST BODY_TYPE PLUMBING
J 0
(-6100 5475);
DISPLAY 0.872340 (-6100 5475);
PAINT GREEN (-6100 5475);
DISPLAY INVISIBLE (-6100 5475);
FORCEPROP 1 LAST HDL_TAP TRUE
J 0
(-5775 5300);
DISPLAY 0.872340 (-5775 5300);
DISPLAY INVISIBLE (-5775 5300);
FORCEPROP 1 LAST PATH I132
J 0
(-6102 5425);
DISPLAY 0.872340 (-6102 5425);
PAINT GREEN (-6102 5425);
DISPLAY INVISIBLE (-6102 5425);
FORCEADD TAP..1
(-6100 5525);
FORCEPROP 3 LASTPIN (-6150 5525) SIG_NAME M_D_CPU1_SA_DQ<30>
J 0
(-6140 5535);
DISPLAY 0.659574 (-6140 5535);
PAINT MONO (-6140 5535);
DISPLAY INVISIBLE (-6140 5535);
FORCEPROP 1 LASTPIN (-6150 5525) BN 30
J 0
(-6162 5533);
DISPLAY 0.489362 (-6162 5533);
PAINT GREEN (-6162 5533);
FORCEPROP 2 LAST CDS_LIB mstr_standard
J 0
(-6100 5525);
DISPLAY 0.723404 (-6100 5525);
PAINT MONO (-6100 5525);
DISPLAY INVISIBLE (-6100 5525);
FORCEPROP 1 LAST BODY_TYPE PLUMBING
J 0
(-6100 5575);
DISPLAY 0.872340 (-6100 5575);
PAINT GREEN (-6100 5575);
DISPLAY INVISIBLE (-6100 5575);
FORCEPROP 1 LAST HDL_TAP TRUE
J 0
(-5775 5400);
DISPLAY 0.872340 (-5775 5400);
DISPLAY INVISIBLE (-5775 5400);
FORCEPROP 1 LAST PATH I133
J 0
(-6102 5525);
DISPLAY 0.872340 (-6102 5525);
PAINT GREEN (-6102 5525);
DISPLAY INVISIBLE (-6102 5525);
FORCEADD TAP..1
(-6100 5575);
FORCEPROP 3 LASTPIN (-6150 5575) SIG_NAME M_D_CPU1_SA_DQ<31>
J 0
(-6140 5585);
DISPLAY 0.659574 (-6140 5585);
PAINT MONO (-6140 5585);
DISPLAY INVISIBLE (-6140 5585);
FORCEPROP 1 LASTPIN (-6150 5575) BN 31
J 0
(-6162 5583);
DISPLAY 0.489362 (-6162 5583);
PAINT GREEN (-6162 5583);
FORCEPROP 2 LAST CDS_LIB mstr_standard
J 0
(-6100 5575);
DISPLAY 0.723404 (-6100 5575);
PAINT MONO (-6100 5575);
DISPLAY INVISIBLE (-6100 5575);
FORCEPROP 1 LAST BODY_TYPE PLUMBING
J 0
(-6100 5625);
DISPLAY 0.872340 (-6100 5625);
PAINT GREEN (-6100 5625);
DISPLAY INVISIBLE (-6100 5625);
FORCEPROP 1 LAST HDL_TAP TRUE
J 0
(-5775 5450);
DISPLAY 0.872340 (-5775 5450);
DISPLAY INVISIBLE (-5775 5450);
FORCEPROP 1 LAST PATH I134
J 0
(-6102 5575);
DISPLAY 0.872340 (-6102 5575);
PAINT GREEN (-6102 5575);
DISPLAY INVISIBLE (-6102 5575);
FORCEADD OFFPAGE..3
(-5425 5625);
FORCEPROP 2 LAST $XR0 40 
J 0
(-5211 5625);
DISPLAY 0.638298 (-5211 5625);
PAINT MONO (-5211 5625);
FORCEPROP 2 LAST PATH I135
J 0
(-5200 5675);
DISPLAY 1.021277 (-5200 5675);
DISPLAY INVISIBLE (-5200 5675);
FORCEPROP 1 LAST COMMENT_BODY TRUE
J 0
(-5475 5525);
DISPLAY 0.872340 (-5475 5525);
PAINT GREEN (-5475 5525);
DISPLAY INVISIBLE (-5475 5525);
FORCEPROP 1 LAST OFFPAGE TRUE
J 0
(-5100 5500);
DISPLAY 0.872340 (-5100 5500);
PAINT GREEN (-5100 5500);
DISPLAY INVISIBLE (-5100 5500);
FORCEPROP 2 LAST CDS_LIB mstr_standard
J 0
(-5425 5625);
DISPLAY 0.723404 (-5425 5625);
PAINT MONO (-5425 5625);
DISPLAY INVISIBLE (-5425 5625);
FORCEADD TAP..1
R 2
(-7800 3525);
FORCEPROP 3 LASTPIN (-7750 3525) SIG_NAME M_D_CPU1_SB_CB<3>
J 0
(-7740 3535);
DISPLAY 0.659574 (-7740 3535);
PAINT MONO (-7740 3535);
DISPLAY INVISIBLE (-7740 3535);
FORCEPROP 1 LASTPIN (-7750 3525) BN 3
J 2
(-7738 3533);
DISPLAY 0.489362 (-7738 3533);
PAINT GREEN (-7738 3533);
FORCEPROP 2 LAST CDS_LIB mstr_standard
J 0
(-7800 3525);
DISPLAY 0.723404 (-7800 3525);
PAINT MONO (-7800 3525);
DISPLAY INVISIBLE (-7800 3525);
FORCEPROP 1 LAST BODY_TYPE PLUMBING
J 2
(-7800 3575);
DISPLAY 0.872340 (-7800 3575);
PAINT GREEN (-7800 3575);
DISPLAY INVISIBLE (-7800 3575);
FORCEPROP 1 LAST HDL_TAP TRUE
J 2
(-8125 3400);
DISPLAY 0.872340 (-8125 3400);
DISPLAY INVISIBLE (-8125 3400);
FORCEPROP 1 LAST PATH I14
J 2
(-7798 3525);
DISPLAY 0.872340 (-7798 3525);
PAINT GREEN (-7798 3525);
DISPLAY INVISIBLE (-7798 3525);
FORCEADD GND..1
(-6525 1200);
FORCEPROP 3 LASTPIN (-6525 1250) SIG_NAME GND\g
J 0
(-6515 1260);
DISPLAY 0.659574 (-6515 1260);
PAINT MONO (-6515 1260);
DISPLAY INVISIBLE (-6515 1260);
FORCEPROP 1 LAST SIZE 1B
J 0
(-6450 1150);
DISPLAY 0.851064 (-6450 1150);
PAINT GREEN (-6450 1150);
DISPLAY INVISIBLE (-6450 1150);
FORCEPROP 2 LAST BOM_COST MEM
J 0
(-6625 1275);
DISPLAY 0.808511 (-6625 1275);
DISPLAY INVISIBLE (-6625 1275);
FORCEPROP 2 LAST CDS_LIB mstr_symbols
J 0
(-6525 1200);
DISPLAY 0.808511 (-6525 1200);
DISPLAY INVISIBLE (-6525 1200);
FORCEPROP 1 LAST BODY_TYPE PLUMBING
J 0
(-6570 1157);
DISPLAY 0.340426 (-6570 1157);
PAINT GREEN (-6570 1157);
DISPLAY INVISIBLE (-6570 1157);
FORCEPROP 1 LAST PATH I145
J 0
(-6450 1200);
DISPLAY 0.872340 (-6450 1200);
PAINT AQUA (-6450 1200);
DISPLAY INVISIBLE (-6450 1200);
FORCEPROP 1 LAST VOLTAGE 0.0
J 0
(-6570 1157);
DISPLAY 0.723404 (-6570 1157);
PAINT SKYBLUE (-6570 1157);
DISPLAY INVISIBLE (-6570 1157);
FORCEPROP 1 LAST HDL_POWER GND
J 0
(-6525 1350);
DISPLAY 0.851064 (-6525 1350);
PAINT GREEN (-6525 1350);
DISPLAY INVISIBLE (-6525 1350);
FORCEADD Q_RES..2
(-6525 1425);
FORCEPROP 1 LAST LOCATION R772
J 0
(-6480 1550);
DISPLAY 0.489362 (-6480 1550);
PAINT SKYBLUE (-6480 1550);
FORCEPROP 0 LAST $SEC 1
J 0
(-6475 1600);
DISPLAY 0.680851 (-6475 1600);
PAINT MONO (-6475 1600);
DISPLAY INVISIBLE (-6475 1600);
FORCEPROP 0 LAST CDS_SEC 1
J 0
(-6475 1600);
DISPLAY 1.021277 (-6475 1600);
DISPLAY INVISIBLE (-6475 1600);
FORCEPROP 1 LASTPIN (-6525 1525) $PN 1
J 0
(-6520 1487);
DISPLAY 0.489362 (-6520 1487);
PAINT MONO (-6520 1487);
FORCEPROP 1 LASTPIN (-6525 1325) $PN 2
J 0
(-6520 1335);
DISPLAY 0.489362 (-6520 1335);
PAINT MONO (-6520 1335);
FORCEPROP 1 LAST WATTAGE 1/16W
J 0
(-6485 1400);
DISPLAY 0.489362 (-6485 1400);
PAINT SKYBLUE (-6485 1400);
FORCEPROP 1 LAST MATERIAL CHIP
J 0
(-6485 1350);
DISPLAY 0.489362 (-6485 1350);
PAINT SKYBLUE (-6485 1350);
FORCEPROP 1 LAST TOLERANCE 1%
J 0
(-6480 1450);
DISPLAY 0.489362 (-6480 1450);
PAINT SKYBLUE (-6480 1450);
FORCEPROP 1 LAST VALUE 35.7K
J 0
(-6480 1500);
DISPLAY 0.489362 (-6480 1500);
PAINT SKYBLUE (-6480 1500);
FORCEPROP 1 LAST PART_NUMBER CS33572FB01
J 0
(-6485 1300);
DISPLAY 0.489362 (-6485 1300);
PAINT SKYBLUE (-6485 1300);
FORCEPROP 1 LAST PACK_TYPE 0402LF
J 0
(-6485 1250);
DISPLAY 0.489362 (-6485 1250);
PAINT SKYBLUE (-6485 1250);
FORCEPROP 2 LAST CDS_LIB pure_quanta
J 0
(-6525 1425);
DISPLAY INVISIBLE (-6525 1425);
FORCEPROP 1 LAST PATH I146
J 0
(-6475 1600);
DISPLAY 0.978723 (-6475 1600);
PAINT WHITE (-6475 1600);
DISPLAY INVISIBLE (-6475 1600);
FORCEADD GND..1
(-2200 2000);
FORCEPROP 3 LASTPIN (-2200 2050) SIG_NAME GND\g
J 0
(-2190 2060);
DISPLAY 0.659574 (-2190 2060);
PAINT MONO (-2190 2060);
DISPLAY INVISIBLE (-2190 2060);
FORCEPROP 2 LAST CDS_LIB mstr_symbols
J 0
(-2200 2000);
DISPLAY 0.723404 (-2200 2000);
DISPLAY INVISIBLE (-2200 2000);
FORCEPROP 1 LAST SIZE 1B
J 0
(-2125 1950);
DISPLAY 0.851064 (-2125 1950);
PAINT GREEN (-2125 1950);
DISPLAY INVISIBLE (-2125 1950);
FORCEPROP 1 LAST BODY_TYPE PLUMBING
J 0
(-2245 1957);
DISPLAY 0.340426 (-2245 1957);
PAINT GREEN (-2245 1957);
DISPLAY INVISIBLE (-2245 1957);
FORCEPROP 1 LAST PATH I147
J 0
(-2125 2000);
DISPLAY 0.872340 (-2125 2000);
PAINT AQUA (-2125 2000);
DISPLAY INVISIBLE (-2125 2000);
FORCEPROP 1 LAST VOLTAGE 0.0
J 0
(-2245 1957);
DISPLAY 0.723404 (-2245 1957);
PAINT SKYBLUE (-2245 1957);
DISPLAY INVISIBLE (-2245 1957);
FORCEPROP 1 LAST HDL_POWER GND
J 0
(-2200 2150);
DISPLAY 0.851064 (-2200 2150);
PAINT GREEN (-2200 2150);
DISPLAY INVISIBLE (-2200 2150);
FORCEADD TAP..1
R 2
(-7800 3475);
FORCEPROP 3 LASTPIN (-7750 3475) SIG_NAME M_D_CPU1_SB_CB<2>
J 0
(-7740 3485);
DISPLAY 0.659574 (-7740 3485);
PAINT MONO (-7740 3485);
DISPLAY INVISIBLE (-7740 3485);
FORCEPROP 1 LASTPIN (-7750 3475) BN 2
J 2
(-7738 3483);
DISPLAY 0.489362 (-7738 3483);
PAINT GREEN (-7738 3483);
FORCEPROP 2 LAST CDS_LIB mstr_standard
J 0
(-7800 3475);
DISPLAY 0.723404 (-7800 3475);
PAINT MONO (-7800 3475);
DISPLAY INVISIBLE (-7800 3475);
FORCEPROP 1 LAST BODY_TYPE PLUMBING
J 2
(-7800 3525);
DISPLAY 0.872340 (-7800 3525);
PAINT GREEN (-7800 3525);
DISPLAY INVISIBLE (-7800 3525);
FORCEPROP 1 LAST HDL_TAP TRUE
J 2
(-8125 3350);
DISPLAY 0.872340 (-8125 3350);
DISPLAY INVISIBLE (-8125 3350);
FORCEPROP 1 LAST PATH I15
J 2
(-7798 3475);
DISPLAY 0.872340 (-7798 3475);
PAINT GREEN (-7798 3475);
DISPLAY INVISIBLE (-7798 3475);
FORCEADD TAP..1
R 2
(-7800 3625);
FORCEPROP 3 LASTPIN (-7750 3625) SIG_NAME M_D_CPU1_SB_CB<5>
J 0
(-7740 3635);
DISPLAY 0.659574 (-7740 3635);
PAINT MONO (-7740 3635);
DISPLAY INVISIBLE (-7740 3635);
FORCEPROP 1 LASTPIN (-7750 3625) BN 5
J 2
(-7738 3633);
DISPLAY 0.489362 (-7738 3633);
PAINT GREEN (-7738 3633);
FORCEPROP 2 LAST CDS_LIB mstr_standard
J 0
(-7800 3625);
DISPLAY 0.723404 (-7800 3625);
PAINT MONO (-7800 3625);
DISPLAY INVISIBLE (-7800 3625);
FORCEPROP 1 LAST BODY_TYPE PLUMBING
J 2
(-7800 3675);
DISPLAY 0.872340 (-7800 3675);
PAINT GREEN (-7800 3675);
DISPLAY INVISIBLE (-7800 3675);
FORCEPROP 1 LAST HDL_TAP TRUE
J 2
(-8125 3500);
DISPLAY 0.872340 (-8125 3500);
DISPLAY INVISIBLE (-8125 3500);
FORCEPROP 1 LAST PATH I16
J 2
(-7798 3625);
DISPLAY 0.872340 (-7798 3625);
PAINT GREEN (-7798 3625);
DISPLAY INVISIBLE (-7798 3625);
FORCEADD SCONN288_DDR506112002KQ..3
(-1300 3750);
FORCEPROP 1 LAST LOCATION J30
J 0
(-1750 5725);
DISPLAY 0.468085 (-1750 5725);
PAINT SKYBLUE (-1750 5725);
FORCEPROP 0 LAST $SEC 3
J 0
(-1750 5875);
DISPLAY 0.680851 (-1750 5875);
PAINT MONO (-1750 5875);
DISPLAY INVISIBLE (-1750 5875);
FORCEPROP 2 LAST CDS_SEC 3
J 0
(-1750 5875);
DISPLAY 1.021277 (-1750 5875);
DISPLAY INVISIBLE (-1750 5875);
FORCEPROP 0 LASTPIN (-700 2150) $PN G1
J 0
(-690 2160);
DISPLAY 0.680851 (-690 2160);
PAINT MONO (-690 2160);
FORCEPROP 0 LASTPIN (-700 2100) $PN G2
J 0
(-690 2110);
DISPLAY 0.680851 (-690 2110);
PAINT MONO (-690 2110);
FORCEPROP 0 LASTPIN (-700 2050) $PN G3
J 0
(-690 2060);
DISPLAY 0.680851 (-690 2060);
PAINT MONO (-690 2060);
FORCEPROP 0 LASTPIN (-1900 5300) $PN 1
J 2
(-1910 5310);
DISPLAY 0.680851 (-1910 5310);
PAINT MONO (-1910 5310);
FORCEPROP 0 LASTPIN (-1900 5350) $PN 145
J 2
(-1910 5360);
DISPLAY 0.680851 (-1910 5360);
PAINT MONO (-1910 5360);
FORCEPROP 0 LASTPIN (-1900 5400) $PN 146
J 2
(-1910 5410);
DISPLAY 0.680851 (-1910 5410);
PAINT MONO (-1910 5410);
FORCEPROP 0 LASTPIN (-700 2250) $PN 6
J 0
(-690 2260);
DISPLAY 0.680851 (-690 2260);
PAINT MONO (-690 2260);
FORCEPROP 0 LASTPIN (-700 2300) $PN 8
J 0
(-690 2310);
DISPLAY 0.680851 (-690 2310);
PAINT MONO (-690 2310);
FORCEPROP 0 LASTPIN (-700 2350) $PN 10
J 0
(-690 2360);
DISPLAY 0.680851 (-690 2360);
PAINT MONO (-690 2360);
FORCEPROP 0 LASTPIN (-700 2400) $PN 13
J 0
(-690 2410);
DISPLAY 0.680851 (-690 2410);
PAINT MONO (-690 2410);
FORCEPROP 0 LASTPIN (-700 2450) $PN 15
J 0
(-690 2460);
DISPLAY 0.680851 (-690 2460);
PAINT MONO (-690 2460);
FORCEPROP 0 LASTPIN (-700 2500) $PN 17
J 0
(-690 2510);
DISPLAY 0.680851 (-690 2510);
PAINT MONO (-690 2510);
FORCEPROP 0 LASTPIN (-700 2550) $PN 19
J 0
(-690 2560);
DISPLAY 0.680851 (-690 2560);
PAINT MONO (-690 2560);
FORCEPROP 0 LASTPIN (-700 2600) $PN 21
J 0
(-690 2610);
DISPLAY 0.680851 (-690 2610);
PAINT MONO (-690 2610);
FORCEPROP 0 LASTPIN (-700 2650) $PN 24
J 0
(-690 2660);
DISPLAY 0.680851 (-690 2660);
PAINT MONO (-690 2660);
FORCEPROP 0 LASTPIN (-700 2700) $PN 26
J 0
(-690 2710);
DISPLAY 0.680851 (-690 2710);
PAINT MONO (-690 2710);
FORCEPROP 0 LASTPIN (-700 2750) $PN 28
J 0
(-690 2760);
DISPLAY 0.680851 (-690 2760);
PAINT MONO (-690 2760);
FORCEPROP 0 LASTPIN (-700 2800) $PN 30
J 0
(-690 2810);
DISPLAY 0.680851 (-690 2810);
PAINT MONO (-690 2810);
FORCEPROP 0 LASTPIN (-700 2850) $PN 32
J 0
(-690 2860);
DISPLAY 0.680851 (-690 2860);
PAINT MONO (-690 2860);
FORCEPROP 0 LASTPIN (-700 2900) $PN 35
J 0
(-690 2910);
DISPLAY 0.680851 (-690 2910);
PAINT MONO (-690 2910);
FORCEPROP 0 LASTPIN (-700 2950) $PN 37
J 0
(-690 2960);
DISPLAY 0.680851 (-690 2960);
PAINT MONO (-690 2960);
FORCEPROP 0 LASTPIN (-700 3000) $PN 39
J 0
(-690 3010);
DISPLAY 0.680851 (-690 3010);
PAINT MONO (-690 3010);
FORCEPROP 0 LASTPIN (-700 3050) $PN 41
J 0
(-690 3060);
DISPLAY 0.680851 (-690 3060);
PAINT MONO (-690 3060);
FORCEPROP 0 LASTPIN (-700 3100) $PN 43
J 0
(-690 3110);
DISPLAY 0.680851 (-690 3110);
PAINT MONO (-690 3110);
FORCEPROP 0 LASTPIN (-700 3150) $PN 46
J 0
(-690 3160);
DISPLAY 0.680851 (-690 3160);
PAINT MONO (-690 3160);
FORCEPROP 0 LASTPIN (-700 3200) $PN 48
J 0
(-690 3210);
DISPLAY 0.680851 (-690 3210);
PAINT MONO (-690 3210);
FORCEPROP 0 LASTPIN (-700 3250) $PN 50
J 0
(-690 3260);
DISPLAY 0.680851 (-690 3260);
PAINT MONO (-690 3260);
FORCEPROP 0 LASTPIN (-700 3300) $PN 52
J 0
(-690 3310);
DISPLAY 0.680851 (-690 3310);
PAINT MONO (-690 3310);
FORCEPROP 0 LASTPIN (-700 3350) $PN 54
J 0
(-690 3360);
DISPLAY 0.680851 (-690 3360);
PAINT MONO (-690 3360);
FORCEPROP 0 LASTPIN (-700 3400) $PN 57
J 0
(-690 3410);
DISPLAY 0.680851 (-690 3410);
PAINT MONO (-690 3410);
FORCEPROP 0 LASTPIN (-700 3450) $PN 59
J 0
(-690 3460);
DISPLAY 0.680851 (-690 3460);
PAINT MONO (-690 3460);
FORCEPROP 0 LASTPIN (-700 3500) $PN 61
J 0
(-690 3510);
DISPLAY 0.680851 (-690 3510);
PAINT MONO (-690 3510);
FORCEPROP 0 LASTPIN (-700 3550) $PN 63
J 0
(-690 3560);
DISPLAY 0.680851 (-690 3560);
PAINT MONO (-690 3560);
FORCEPROP 0 LASTPIN (-700 3600) $PN 65
J 0
(-690 3610);
DISPLAY 0.680851 (-690 3610);
PAINT MONO (-690 3610);
FORCEPROP 0 LASTPIN (-700 3650) $PN 67
J 0
(-690 3660);
DISPLAY 0.680851 (-690 3660);
PAINT MONO (-690 3660);
FORCEPROP 0 LASTPIN (-700 3700) $PN 69
J 0
(-690 3710);
DISPLAY 0.680851 (-690 3710);
PAINT MONO (-690 3710);
FORCEPROP 0 LASTPIN (-700 3750) $PN 71
J 0
(-690 3760);
DISPLAY 0.680851 (-690 3760);
PAINT MONO (-690 3760);
FORCEPROP 0 LASTPIN (-700 3800) $PN 73
J 0
(-690 3810);
DISPLAY 0.680851 (-690 3810);
PAINT MONO (-690 3810);
FORCEPROP 0 LASTPIN (-700 3850) $PN 75
J 0
(-690 3860);
DISPLAY 0.680851 (-690 3860);
PAINT MONO (-690 3860);
FORCEPROP 0 LASTPIN (-700 3900) $PN 77
J 0
(-690 3910);
DISPLAY 0.680851 (-690 3910);
PAINT MONO (-690 3910);
FORCEPROP 0 LASTPIN (-700 3950) $PN 79
J 0
(-690 3960);
DISPLAY 0.680851 (-690 3960);
PAINT MONO (-690 3960);
FORCEPROP 0 LASTPIN (-700 4000) $PN 81
J 0
(-690 4010);
DISPLAY 0.680851 (-690 4010);
PAINT MONO (-690 4010);
FORCEPROP 0 LASTPIN (-700 4050) $PN 83
J 0
(-690 4060);
DISPLAY 0.680851 (-690 4060);
PAINT MONO (-690 4060);
FORCEPROP 0 LASTPIN (-700 4100) $PN 85
J 0
(-690 4110);
DISPLAY 0.680851 (-690 4110);
PAINT MONO (-690 4110);
FORCEPROP 0 LASTPIN (-700 4150) $PN 88
J 0
(-690 4160);
DISPLAY 0.680851 (-690 4160);
PAINT MONO (-690 4160);
FORCEPROP 0 LASTPIN (-700 4200) $PN 90
J 0
(-690 4210);
DISPLAY 0.680851 (-690 4210);
PAINT MONO (-690 4210);
FORCEPROP 0 LASTPIN (-700 4250) $PN 92
J 0
(-690 4260);
DISPLAY 0.680851 (-690 4260);
PAINT MONO (-690 4260);
FORCEPROP 0 LASTPIN (-700 4300) $PN 95
J 0
(-690 4310);
DISPLAY 0.680851 (-690 4310);
PAINT MONO (-690 4310);
FORCEPROP 0 LASTPIN (-700 4350) $PN 97
J 0
(-690 4360);
DISPLAY 0.680851 (-690 4360);
PAINT MONO (-690 4360);
FORCEPROP 0 LASTPIN (-700 4400) $PN 99
J 0
(-690 4410);
DISPLAY 0.680851 (-690 4410);
PAINT MONO (-690 4410);
FORCEPROP 0 LASTPIN (-700 4450) $PN 101
J 0
(-690 4460);
DISPLAY 0.680851 (-690 4460);
PAINT MONO (-690 4460);
FORCEPROP 0 LASTPIN (-700 4500) $PN 103
J 0
(-690 4510);
DISPLAY 0.680851 (-690 4510);
PAINT MONO (-690 4510);
FORCEPROP 0 LASTPIN (-700 4550) $PN 106
J 0
(-690 4560);
DISPLAY 0.680851 (-690 4560);
PAINT MONO (-690 4560);
FORCEPROP 0 LASTPIN (-700 4600) $PN 108
J 0
(-690 4610);
DISPLAY 0.680851 (-690 4610);
PAINT MONO (-690 4610);
FORCEPROP 0 LASTPIN (-700 4650) $PN 110
J 0
(-690 4660);
DISPLAY 0.680851 (-690 4660);
PAINT MONO (-690 4660);
FORCEPROP 0 LASTPIN (-700 4700) $PN 112
J 0
(-690 4710);
DISPLAY 0.680851 (-690 4710);
PAINT MONO (-690 4710);
FORCEPROP 0 LASTPIN (-700 4750) $PN 114
J 0
(-690 4760);
DISPLAY 0.680851 (-690 4760);
PAINT MONO (-690 4760);
FORCEPROP 0 LASTPIN (-700 4800) $PN 117
J 0
(-690 4810);
DISPLAY 0.680851 (-690 4810);
PAINT MONO (-690 4810);
FORCEPROP 0 LASTPIN (-700 4850) $PN 119
J 0
(-690 4860);
DISPLAY 0.680851 (-690 4860);
PAINT MONO (-690 4860);
FORCEPROP 0 LASTPIN (-700 4900) $PN 121
J 0
(-690 4910);
DISPLAY 0.680851 (-690 4910);
PAINT MONO (-690 4910);
FORCEPROP 0 LASTPIN (-700 4950) $PN 123
J 0
(-690 4960);
DISPLAY 0.680851 (-690 4960);
PAINT MONO (-690 4960);
FORCEPROP 0 LASTPIN (-700 5000) $PN 125
J 0
(-690 5010);
DISPLAY 0.680851 (-690 5010);
PAINT MONO (-690 5010);
FORCEPROP 0 LASTPIN (-700 5050) $PN 128
J 0
(-690 5060);
DISPLAY 0.680851 (-690 5060);
PAINT MONO (-690 5060);
FORCEPROP 0 LASTPIN (-700 5100) $PN 130
J 0
(-690 5110);
DISPLAY 0.680851 (-690 5110);
PAINT MONO (-690 5110);
FORCEPROP 0 LASTPIN (-700 5150) $PN 132
J 0
(-690 5160);
DISPLAY 0.680851 (-690 5160);
PAINT MONO (-690 5160);
FORCEPROP 0 LASTPIN (-700 5200) $PN 134
J 0
(-690 5210);
DISPLAY 0.680851 (-690 5210);
PAINT MONO (-690 5210);
FORCEPROP 0 LASTPIN (-700 5250) $PN 136
J 0
(-690 5260);
DISPLAY 0.680851 (-690 5260);
PAINT MONO (-690 5260);
FORCEPROP 0 LASTPIN (-700 5300) $PN 139
J 0
(-690 5310);
DISPLAY 0.680851 (-690 5310);
PAINT MONO (-690 5310);
FORCEPROP 0 LASTPIN (-700 5350) $PN 141
J 0
(-690 5360);
DISPLAY 0.680851 (-690 5360);
PAINT MONO (-690 5360);
FORCEPROP 0 LASTPIN (-700 5400) $PN 143
J 0
(-690 5410);
DISPLAY 0.680851 (-690 5410);
PAINT MONO (-690 5410);
FORCEPROP 0 LASTPIN (-1900 2150) $PN 151
J 2
(-1910 2160);
DISPLAY 0.680851 (-1910 2160);
PAINT MONO (-1910 2160);
FORCEPROP 0 LASTPIN (-1900 2200) $PN 153
J 2
(-1910 2210);
DISPLAY 0.680851 (-1910 2210);
PAINT MONO (-1910 2210);
FORCEPROP 0 LASTPIN (-1900 2250) $PN 155
J 2
(-1910 2260);
DISPLAY 0.680851 (-1910 2260);
PAINT MONO (-1910 2260);
FORCEPROP 0 LASTPIN (-1900 2300) $PN 158
J 2
(-1910 2310);
DISPLAY 0.680851 (-1910 2310);
PAINT MONO (-1910 2310);
FORCEPROP 0 LASTPIN (-1900 2350) $PN 160
J 2
(-1910 2360);
DISPLAY 0.680851 (-1910 2360);
PAINT MONO (-1910 2360);
FORCEPROP 0 LASTPIN (-1900 2400) $PN 162
J 2
(-1910 2410);
DISPLAY 0.680851 (-1910 2410);
PAINT MONO (-1910 2410);
FORCEPROP 0 LASTPIN (-1900 2450) $PN 164
J 2
(-1910 2460);
DISPLAY 0.680851 (-1910 2460);
PAINT MONO (-1910 2460);
FORCEPROP 0 LASTPIN (-1900 2500) $PN 166
J 2
(-1910 2510);
DISPLAY 0.680851 (-1910 2510);
PAINT MONO (-1910 2510);
FORCEPROP 0 LASTPIN (-1900 2550) $PN 169
J 2
(-1910 2560);
DISPLAY 0.680851 (-1910 2560);
PAINT MONO (-1910 2560);
FORCEPROP 0 LASTPIN (-1900 2600) $PN 171
J 2
(-1910 2610);
DISPLAY 0.680851 (-1910 2610);
PAINT MONO (-1910 2610);
FORCEPROP 0 LASTPIN (-1900 2650) $PN 173
J 2
(-1910 2660);
DISPLAY 0.680851 (-1910 2660);
PAINT MONO (-1910 2660);
FORCEPROP 0 LASTPIN (-1900 2700) $PN 175
J 2
(-1910 2710);
DISPLAY 0.680851 (-1910 2710);
PAINT MONO (-1910 2710);
FORCEPROP 0 LASTPIN (-1900 2750) $PN 177
J 2
(-1910 2760);
DISPLAY 0.680851 (-1910 2760);
PAINT MONO (-1910 2760);
FORCEPROP 0 LASTPIN (-1900 2800) $PN 180
J 2
(-1910 2810);
DISPLAY 0.680851 (-1910 2810);
PAINT MONO (-1910 2810);
FORCEPROP 0 LASTPIN (-1900 2850) $PN 182
J 2
(-1910 2860);
DISPLAY 0.680851 (-1910 2860);
PAINT MONO (-1910 2860);
FORCEPROP 0 LASTPIN (-1900 2900) $PN 184
J 2
(-1910 2910);
DISPLAY 0.680851 (-1910 2910);
PAINT MONO (-1910 2910);
FORCEPROP 0 LASTPIN (-1900 2950) $PN 186
J 2
(-1910 2960);
DISPLAY 0.680851 (-1910 2960);
PAINT MONO (-1910 2960);
FORCEPROP 0 LASTPIN (-1900 3000) $PN 188
J 2
(-1910 3010);
DISPLAY 0.680851 (-1910 3010);
PAINT MONO (-1910 3010);
FORCEPROP 0 LASTPIN (-1900 3050) $PN 191
J 2
(-1910 3060);
DISPLAY 0.680851 (-1910 3060);
PAINT MONO (-1910 3060);
FORCEPROP 0 LASTPIN (-1900 3100) $PN 193
J 2
(-1910 3110);
DISPLAY 0.680851 (-1910 3110);
PAINT MONO (-1910 3110);
FORCEPROP 0 LASTPIN (-1900 3150) $PN 195
J 2
(-1910 3160);
DISPLAY 0.680851 (-1910 3160);
PAINT MONO (-1910 3160);
FORCEPROP 0 LASTPIN (-1900 3200) $PN 197
J 2
(-1910 3210);
DISPLAY 0.680851 (-1910 3210);
PAINT MONO (-1910 3210);
FORCEPROP 0 LASTPIN (-1900 3250) $PN 199
J 2
(-1910 3260);
DISPLAY 0.680851 (-1910 3260);
PAINT MONO (-1910 3260);
FORCEPROP 0 LASTPIN (-1900 3300) $PN 202
J 2
(-1910 3310);
DISPLAY 0.680851 (-1910 3310);
PAINT MONO (-1910 3310);
FORCEPROP 0 LASTPIN (-1900 3350) $PN 204
J 2
(-1910 3360);
DISPLAY 0.680851 (-1910 3360);
PAINT MONO (-1910 3360);
FORCEPROP 0 LASTPIN (-1900 3400) $PN 206
J 2
(-1910 3410);
DISPLAY 0.680851 (-1910 3410);
PAINT MONO (-1910 3410);
FORCEPROP 0 LASTPIN (-1900 3450) $PN 208
J 2
(-1910 3460);
DISPLAY 0.680851 (-1910 3460);
PAINT MONO (-1910 3460);
FORCEPROP 0 LASTPIN (-1900 3500) $PN 210
J 2
(-1910 3510);
DISPLAY 0.680851 (-1910 3510);
PAINT MONO (-1910 3510);
FORCEPROP 0 LASTPIN (-1900 3550) $PN 212
J 2
(-1910 3560);
DISPLAY 0.680851 (-1910 3560);
PAINT MONO (-1910 3560);
FORCEPROP 0 LASTPIN (-1900 3600) $PN 214
J 2
(-1910 3610);
DISPLAY 0.680851 (-1910 3610);
PAINT MONO (-1910 3610);
FORCEPROP 0 LASTPIN (-1900 3650) $PN 216
J 2
(-1910 3660);
DISPLAY 0.680851 (-1910 3660);
PAINT MONO (-1910 3660);
FORCEPROP 0 LASTPIN (-1900 3700) $PN 219
J 2
(-1910 3710);
DISPLAY 0.680851 (-1910 3710);
PAINT MONO (-1910 3710);
FORCEPROP 0 LASTPIN (-1900 3750) $PN 222
J 2
(-1910 3760);
DISPLAY 0.680851 (-1910 3760);
PAINT MONO (-1910 3760);
FORCEPROP 0 LASTPIN (-1900 3800) $PN 224
J 2
(-1910 3810);
DISPLAY 0.680851 (-1910 3810);
PAINT MONO (-1910 3810);
FORCEPROP 0 LASTPIN (-1900 3850) $PN 226
J 2
(-1910 3860);
DISPLAY 0.680851 (-1910 3860);
PAINT MONO (-1910 3860);
FORCEPROP 0 LASTPIN (-1900 3900) $PN 228
J 2
(-1910 3910);
DISPLAY 0.680851 (-1910 3910);
PAINT MONO (-1910 3910);
FORCEPROP 0 LASTPIN (-1900 3950) $PN 230
J 2
(-1910 3960);
DISPLAY 0.680851 (-1910 3960);
PAINT MONO (-1910 3960);
FORCEPROP 0 LASTPIN (-1900 4000) $PN 233
J 2
(-1910 4010);
DISPLAY 0.680851 (-1910 4010);
PAINT MONO (-1910 4010);
FORCEPROP 0 LASTPIN (-1900 4050) $PN 235
J 2
(-1910 4060);
DISPLAY 0.680851 (-1910 4060);
PAINT MONO (-1910 4060);
FORCEPROP 0 LASTPIN (-1900 4100) $PN 237
J 2
(-1910 4110);
DISPLAY 0.680851 (-1910 4110);
PAINT MONO (-1910 4110);
FORCEPROP 0 LASTPIN (-1900 4150) $PN 240
J 2
(-1910 4160);
DISPLAY 0.680851 (-1910 4160);
PAINT MONO (-1910 4160);
FORCEPROP 0 LASTPIN (-1900 4200) $PN 242
J 2
(-1910 4210);
DISPLAY 0.680851 (-1910 4210);
PAINT MONO (-1910 4210);
FORCEPROP 0 LASTPIN (-1900 4250) $PN 244
J 2
(-1910 4260);
DISPLAY 0.680851 (-1910 4260);
PAINT MONO (-1910 4260);
FORCEPROP 0 LASTPIN (-1900 4300) $PN 246
J 2
(-1910 4310);
DISPLAY 0.680851 (-1910 4310);
PAINT MONO (-1910 4310);
FORCEPROP 0 LASTPIN (-1900 4350) $PN 248
J 2
(-1910 4360);
DISPLAY 0.680851 (-1910 4360);
PAINT MONO (-1910 4360);
FORCEPROP 0 LASTPIN (-1900 4400) $PN 251
J 2
(-1910 4410);
DISPLAY 0.680851 (-1910 4410);
PAINT MONO (-1910 4410);
FORCEPROP 0 LASTPIN (-1900 4450) $PN 253
J 2
(-1910 4460);
DISPLAY 0.680851 (-1910 4460);
PAINT MONO (-1910 4460);
FORCEPROP 0 LASTPIN (-1900 4500) $PN 255
J 2
(-1910 4510);
DISPLAY 0.680851 (-1910 4510);
PAINT MONO (-1910 4510);
FORCEPROP 0 LASTPIN (-1900 4550) $PN 257
J 2
(-1910 4560);
DISPLAY 0.680851 (-1910 4560);
PAINT MONO (-1910 4560);
FORCEPROP 0 LASTPIN (-1900 4600) $PN 259
J 2
(-1910 4610);
DISPLAY 0.680851 (-1910 4610);
PAINT MONO (-1910 4610);
FORCEPROP 0 LASTPIN (-1900 4650) $PN 262
J 2
(-1910 4660);
DISPLAY 0.680851 (-1910 4660);
PAINT MONO (-1910 4660);
FORCEPROP 0 LASTPIN (-1900 4700) $PN 264
J 2
(-1910 4710);
DISPLAY 0.680851 (-1910 4710);
PAINT MONO (-1910 4710);
FORCEPROP 0 LASTPIN (-1900 4750) $PN 266
J 2
(-1910 4760);
DISPLAY 0.680851 (-1910 4760);
PAINT MONO (-1910 4760);
FORCEPROP 0 LASTPIN (-1900 4800) $PN 268
J 2
(-1910 4810);
DISPLAY 0.680851 (-1910 4810);
PAINT MONO (-1910 4810);
FORCEPROP 0 LASTPIN (-1900 4850) $PN 270
J 2
(-1910 4860);
DISPLAY 0.680851 (-1910 4860);
PAINT MONO (-1910 4860);
FORCEPROP 0 LASTPIN (-1900 4900) $PN 273
J 2
(-1910 4910);
DISPLAY 0.680851 (-1910 4910);
PAINT MONO (-1910 4910);
FORCEPROP 0 LASTPIN (-1900 4950) $PN 275
J 2
(-1910 4960);
DISPLAY 0.680851 (-1910 4960);
PAINT MONO (-1910 4960);
FORCEPROP 0 LASTPIN (-1900 5000) $PN 277
J 2
(-1910 5010);
DISPLAY 0.680851 (-1910 5010);
PAINT MONO (-1910 5010);
FORCEPROP 0 LASTPIN (-1900 5050) $PN 279
J 2
(-1910 5060);
DISPLAY 0.680851 (-1910 5060);
PAINT MONO (-1910 5060);
FORCEPROP 0 LASTPIN (-1900 5100) $PN 281
J 2
(-1910 5110);
DISPLAY 0.680851 (-1910 5110);
PAINT MONO (-1910 5110);
FORCEPROP 0 LASTPIN (-1900 5150) $PN 284
J 2
(-1910 5160);
DISPLAY 0.680851 (-1910 5160);
PAINT MONO (-1910 5160);
FORCEPROP 0 LASTPIN (-1900 5200) $PN 286
J 2
(-1910 5210);
DISPLAY 0.680851 (-1910 5210);
PAINT MONO (-1910 5210);
FORCEPROP 0 LASTPIN (-1900 5250) $PN 288
J 2
(-1910 5260);
DISPLAY 0.680851 (-1910 5260);
PAINT MONO (-1910 5260);
FORCEPROP 2 LAST PART_TYPE SMLF
J 0
(-1750 5825);
DISPLAY 1.021277 (-1750 5825);
FORCEPROP 1 LAST MATERIAL IO
J 0
(-1750 5575);
DISPLAY 0.468085 (-1750 5575);
PAINT SKYBLUE (-1750 5575);
FORCEPROP 2 LAST VALUE SCONN288_DDR506112002KQ
J 0
(-1750 5775);
DISPLAY 0.489362 (-1750 5775);
PAINT SKYBLUE (-1750 5775);
FORCEPROP 1 LAST PART_NUMBER DFHST8FS479
J 0
(-1750 5650);
DISPLAY 0.468085 (-1750 5650);
PAINT SKYBLUE (-1750 5650);
FORCEPROP 1 LAST CDS_LMAN_SYM_OUTLINE -450,1800,450,-1750
J 0
(-1300 3750);
DISPLAY 0.468085 (-1300 3750);
PAINT GREEN (-1300 3750);
DISPLAY INVISIBLE (-1300 3750);
FORCEPROP 1 LAST PATH I161
J 0
(-1300 3750);
DISPLAY 0.723404 (-1300 3750);
PAINT GREEN (-1300 3750);
DISPLAY INVISIBLE (-1300 3750);
FORCEPROP 1 LAST NEEDS_NO_SIZE TRUE
J 0
(-1300 3750);
DISPLAY 0.723404 (-1300 3750);
PAINT GREEN (-1300 3750);
DISPLAY INVISIBLE (-1300 3750);
FORCEPROP 2 LAST CDS_LIB pure_quanta
J 0
(-1300 3750);
DISPLAY INVISIBLE (-1300 3750);
FORCEADD GND..1
(-400 1800);
FORCEPROP 3 LASTPIN (-400 1850) SIG_NAME GND\g
J 0
(-390 1860);
DISPLAY 0.659574 (-390 1860);
PAINT MONO (-390 1860);
DISPLAY INVISIBLE (-390 1860);
FORCEPROP 1 LAST SIZE 1B
J 0
(-325 1750);
DISPLAY 0.851064 (-325 1750);
PAINT GREEN (-325 1750);
DISPLAY INVISIBLE (-325 1750);
FORCEPROP 2 LAST CDS_LIB mstr_symbols
J 0
(-400 1800);
DISPLAY 0.723404 (-400 1800);
DISPLAY INVISIBLE (-400 1800);
FORCEPROP 1 LAST BODY_TYPE PLUMBING
J 0
(-445 1757);
DISPLAY 0.340426 (-445 1757);
PAINT GREEN (-445 1757);
DISPLAY INVISIBLE (-445 1757);
FORCEPROP 1 LAST PATH I162
J 0
(-325 1800);
DISPLAY 0.872340 (-325 1800);
PAINT AQUA (-325 1800);
DISPLAY INVISIBLE (-325 1800);
FORCEPROP 1 LAST VOLTAGE 0.0
J 0
(-445 1757);
DISPLAY 0.723404 (-445 1757);
PAINT SKYBLUE (-445 1757);
DISPLAY INVISIBLE (-445 1757);
FORCEPROP 1 LAST HDL_POWER GND
J 0
(-400 1950);
DISPLAY 0.851064 (-400 1950);
PAINT GREEN (-400 1950);
DISPLAY INVISIBLE (-400 1950);
FORCEADD TAP..1
R 2
(-7800 3575);
FORCEPROP 3 LASTPIN (-7750 3575) SIG_NAME M_D_CPU1_SB_CB<4>
J 0
(-7740 3585);
DISPLAY 0.659574 (-7740 3585);
PAINT MONO (-7740 3585);
DISPLAY INVISIBLE (-7740 3585);
FORCEPROP 1 LASTPIN (-7750 3575) BN 4
J 2
(-7738 3583);
DISPLAY 0.489362 (-7738 3583);
PAINT GREEN (-7738 3583);
FORCEPROP 2 LAST CDS_LIB mstr_standard
J 0
(-7800 3575);
DISPLAY 0.723404 (-7800 3575);
PAINT MONO (-7800 3575);
DISPLAY INVISIBLE (-7800 3575);
FORCEPROP 1 LAST BODY_TYPE PLUMBING
J 2
(-7800 3625);
DISPLAY 0.872340 (-7800 3625);
PAINT GREEN (-7800 3625);
DISPLAY INVISIBLE (-7800 3625);
FORCEPROP 1 LAST HDL_TAP TRUE
J 2
(-8125 3450);
DISPLAY 0.872340 (-8125 3450);
DISPLAY INVISIBLE (-8125 3450);
FORCEPROP 1 LAST PATH I17
J 2
(-7798 3575);
DISPLAY 0.872340 (-7798 3575);
PAINT GREEN (-7798 3575);
DISPLAY INVISIBLE (-7798 3575);
FORCEADD OFFPAGE..6
(-8400 3025);
FORCEPROP 2 LAST $XR5 136 
J 0
(-9189 3025);
DISPLAY 0.638298 (-9189 3025);
PAINT MONO (-9189 3025);
FORCEPROP 2 LAST $XR4 102 
J 0
(-9069 3025);
DISPLAY 0.638298 (-9069 3025);
PAINT MONO (-9069 3025);
FORCEPROP 2 LAST $XR3 101 
J 0
(-8949 3025);
DISPLAY 0.638298 (-8949 3025);
PAINT MONO (-8949 3025);
FORCEPROP 2 LAST $XR2 99 
J 0
(-8829 3025);
DISPLAY 0.638298 (-8829 3025);
PAINT MONO (-8829 3025);
FORCEPROP 2 LAST $XR1 98 
J 0
(-8739 3025);
DISPLAY 0.638298 (-8739 3025);
PAINT MONO (-8739 3025);
FORCEPROP 2 LAST $XR0 97 
J 0
(-8649 3025);
DISPLAY 0.638298 (-8649 3025);
PAINT MONO (-8649 3025);
FORCEPROP 2 LAST PATH I179
J 0
(-8675 3075);
DISPLAY 1.021277 (-8675 3075);
DISPLAY INVISIBLE (-8675 3075);
FORCEPROP 1 LAST COMMENT_BODY TRUE
J 0
(-8300 2950);
DISPLAY 0.872340 (-8300 2950);
PAINT GREEN (-8300 2950);
DISPLAY INVISIBLE (-8300 2950);
FORCEPROP 1 LAST OFFPAGE TRUE
J 0
(-8075 2900);
DISPLAY 0.872340 (-8075 2900);
PAINT GREEN (-8075 2900);
DISPLAY INVISIBLE (-8075 2900);
FORCEPROP 2 LAST CDS_LIB mstr_standard
J 0
(-8400 3025);
DISPLAY 0.808511 (-8400 3025);
DISPLAY INVISIBLE (-8400 3025);
FORCEADD TAP..1
R 2
(-7800 3675);
FORCEPROP 3 LASTPIN (-7750 3675) SIG_NAME M_D_CPU1_SB_CB<6>
J 0
(-7740 3685);
DISPLAY 0.659574 (-7740 3685);
PAINT MONO (-7740 3685);
DISPLAY INVISIBLE (-7740 3685);
FORCEPROP 1 LASTPIN (-7750 3675) BN 6
J 2
(-7738 3683);
DISPLAY 0.489362 (-7738 3683);
PAINT GREEN (-7738 3683);
FORCEPROP 2 LAST CDS_LIB mstr_standard
J 0
(-7800 3675);
DISPLAY 0.723404 (-7800 3675);
PAINT MONO (-7800 3675);
DISPLAY INVISIBLE (-7800 3675);
FORCEPROP 1 LAST BODY_TYPE PLUMBING
J 2
(-7800 3725);
DISPLAY 0.872340 (-7800 3725);
PAINT GREEN (-7800 3725);
DISPLAY INVISIBLE (-7800 3725);
FORCEPROP 1 LAST HDL_TAP TRUE
J 2
(-8125 3550);
DISPLAY 0.872340 (-8125 3550);
DISPLAY INVISIBLE (-8125 3550);
FORCEPROP 1 LAST PATH I18
J 2
(-7798 3675);
DISPLAY 0.872340 (-7798 3675);
PAINT GREEN (-7798 3675);
DISPLAY INVISIBLE (-7798 3675);
FORCEADD Q_CAP..1
R 2
(-8750 3400);
FORCEPROP 1 LAST LOCATION C148
J 2
(-8800 3500);
DISPLAY 0.489362 (-8800 3500);
PAINT SKYBLUE (-8800 3500);
FORCEPROP 0 LAST $SEC 1
J 0
(-8800 3550);
DISPLAY 0.680851 (-8800 3550);
PAINT MONO (-8800 3550);
DISPLAY INVISIBLE (-8800 3550);
FORCEPROP 0 LAST CDS_SEC 1
J 0
(-8800 3550);
DISPLAY 1.021277 (-8800 3550);
DISPLAY INVISIBLE (-8800 3550);
FORCEPROP 1 LASTPIN (-8750 3500) $PN 1
J 2
(-8760 3480);
DISPLAY 0.489362 (-8760 3480);
PAINT MONO (-8760 3480);
FORCEPROP 1 LASTPIN (-8750 3300) $PN 2
J 2
(-8760 3280);
DISPLAY 0.489362 (-8760 3280);
PAINT MONO (-8760 3280);
FORCEPROP 1 LAST MATERIAL X7R
J 2
(-8800 3300);
DISPLAY 0.489362 (-8800 3300);
PAINT SKYBLUE (-8800 3300);
FORCEPROP 1 LAST TOLERANCE 10%
J 2
(-8800 3350);
DISPLAY 0.489362 (-8800 3350);
PAINT SKYBLUE (-8800 3350);
FORCEPROP 1 LAST VALUE 0.1UF
J 2
(-8800 3450);
DISPLAY 0.489362 (-8800 3450);
PAINT SKYBLUE (-8800 3450);
FORCEPROP 1 LAST PART_NUMBER CH4104K1B00
J 2
(-8800 3250);
DISPLAY 0.489362 (-8800 3250);
PAINT SKYBLUE (-8800 3250);
FORCEPROP 1 LAST VOLTAGE 25V
J 2
(-8800 3400);
DISPLAY 0.489362 (-8800 3400);
PAINT SKYBLUE (-8800 3400);
FORCEPROP 1 LAST PACK_TYPE 0402
J 2
(-8800 3200);
DISPLAY 0.489362 (-8800 3200);
PAINT SKYBLUE (-8800 3200);
FORCEPROP 2 LAST CDS_LIB pure_quanta
J 0
(-8750 3400);
DISPLAY INVISIBLE (-8750 3400);
FORCEPROP 0 LAST BOM_COST MEM
J 2
(-8805 3545);
DISPLAY 0.595745 (-8805 3545);
PAINT MONO (-8805 3545);
DISPLAY INVISIBLE (-8805 3545);
FORCEPROP 1 LAST PATH I185
J 2
(-8800 3550);
DISPLAY 0.978723 (-8800 3550);
PAINT WHITE (-8800 3550);
DISPLAY INVISIBLE (-8800 3550);
FORCEPROP 0 LAST ROOM MEM_CH_A_CPU0_DIMM1
J 2
(-8805 3545);
DISPLAY 0.595745 (-8805 3545);
PAINT RED (-8805 3545);
DISPLAY INVISIBLE (-8805 3545);
FORCEADD GND..1
(-8750 3175);
FORCEPROP 3 LASTPIN (-8750 3225) SIG_NAME GND\g
J 0
(-8740 3235);
DISPLAY 0.659574 (-8740 3235);
PAINT MONO (-8740 3235);
DISPLAY INVISIBLE (-8740 3235);
FORCEPROP 2 LAST CDS_LIB mstr_symbols
J 0
(-8750 3175);
DISPLAY 0.808511 (-8750 3175);
DISPLAY INVISIBLE (-8750 3175);
FORCEPROP 1 LAST SIZE 1B
J 0
(-8675 3125);
DISPLAY 0.723404 (-8675 3125);
PAINT GREEN (-8675 3125);
DISPLAY INVISIBLE (-8675 3125);
FORCEPROP 2 LAST BOM_COST MEM
J 0
(-8725 3300);
DISPLAY 0.659574 (-8725 3300);
DISPLAY INVISIBLE (-8725 3300);
FORCEPROP 1 LAST BODY_TYPE PLUMBING
J 0
(-8795 3132);
DISPLAY 0.276596 (-8795 3132);
PAINT GREEN (-8795 3132);
DISPLAY INVISIBLE (-8795 3132);
FORCEPROP 1 LAST PATH I186
J 0
(-8675 3175);
DISPLAY 0.872340 (-8675 3175);
PAINT AQUA (-8675 3175);
DISPLAY INVISIBLE (-8675 3175);
FORCEPROP 1 LAST VOLTAGE 0
J 0
(-8770 3270);
DISPLAY 0.829787 (-8770 3270);
PAINT SKYBLUE (-8770 3270);
DISPLAY INVISIBLE (-8770 3270);
FORCEPROP 2 LAST ROOM MEM_EFGH_DECOUPLING_CAPS
J 0
(-8725 3250);
DISPLAY 0.659574 (-8725 3250);
PAINT RED (-8725 3250);
DISPLAY INVISIBLE (-8725 3250);
FORCEPROP 1 LAST HDL_POWER GND
J 0
(-8750 3325);
DISPLAY 0.723404 (-8750 3325);
PAINT GREEN (-8750 3325);
DISPLAY INVISIBLE (-8750 3325);
FORCEADD OFFPAGE..6
(-9100 2325);
FORCEPROP 2 LAST $XR5 81 
J 0
(-9439 2361);
DISPLAY 0.638298 (-9439 2361);
PAINT MONO (-9439 2361);
FORCEPROP 2 LAST $XR4 102 
J 0
(-9349 2361);
DISPLAY 0.638298 (-9349 2361);
PAINT MONO (-9349 2361);
FORCEPROP 2 LAST $XR3 101 
J 0
(-9439 2289);
DISPLAY 0.638298 (-9439 2289);
PAINT MONO (-9439 2289);
FORCEPROP 2 LAST $XR2 99 
J 0
(-9529 2325);
DISPLAY 0.638298 (-9529 2325);
PAINT MONO (-9529 2325);
FORCEPROP 2 LAST $XR1 98 
J 0
(-9439 2325);
DISPLAY 0.638298 (-9439 2325);
PAINT MONO (-9439 2325);
FORCEPROP 2 LAST $XR0 97 
J 0
(-9349 2325);
DISPLAY 0.638298 (-9349 2325);
PAINT MONO (-9349 2325);
FORCEPROP 2 LAST PATH I187
J 0
(-9050 2400);
DISPLAY 1.021277 (-9050 2400);
DISPLAY INVISIBLE (-9050 2400);
FORCEPROP 1 LAST COMMENT_BODY TRUE
J 0
(-9000 2250);
DISPLAY 0.872340 (-9000 2250);
PAINT GREEN (-9000 2250);
DISPLAY INVISIBLE (-9000 2250);
FORCEPROP 1 LAST OFFPAGE TRUE
J 0
(-8775 2200);
DISPLAY 0.872340 (-8775 2200);
PAINT GREEN (-8775 2200);
DISPLAY INVISIBLE (-8775 2200);
FORCEPROP 2 LAST CDS_LIB mstr_standard
J 0
(-9100 2325);
DISPLAY 0.808511 (-9100 2325);
DISPLAY INVISIBLE (-9100 2325);
FORCEADD Q_RES..1
R 2
(-8600 2325);
FORCEPROP 1 LAST LOCATION R306
J 2
(-8575 2350);
DISPLAY 0.489362 (-8575 2350);
PAINT SKYBLUE (-8575 2350);
FORCEPROP 0 LAST $SEC 1
J 0
(-8575 2400);
DISPLAY 0.680851 (-8575 2400);
PAINT MONO (-8575 2400);
DISPLAY INVISIBLE (-8575 2400);
FORCEPROP 0 LAST CDS_SEC 1
J 0
(-8575 2400);
DISPLAY 1.021277 (-8575 2400);
DISPLAY INVISIBLE (-8575 2400);
FORCEPROP 1 LASTPIN (-8500 2325) $PN 1
J 2
(-8512 2337);
DISPLAY 0.489362 (-8512 2337);
PAINT MONO (-8512 2337);
FORCEPROP 1 LASTPIN (-8700 2325) $PN 2
J 2
(-8662 2337);
DISPLAY 0.489362 (-8662 2337);
PAINT MONO (-8662 2337);
FORCEPROP 1 LAST VALUE 0
J 0
(-8600 2275);
DISPLAY 0.489362 (-8600 2275);
PAINT SKYBLUE (-8600 2275);
FORCEPROP 2 LAST CDS_LIB pure_quanta
J 0
(-8600 2325);
DISPLAY INVISIBLE (-8600 2325);
FORCEPROP 2 LAST BOM_COST MEM
J 0
(-8625 2475);
DISPLAY 0.744681 (-8625 2475);
PAINT WHITE (-8625 2475);
DISPLAY INVISIBLE (-8625 2475);
FORCEPROP 1 LAST PATH I188
J 2
(-8550 2475);
DISPLAY 0.978723 (-8550 2475);
PAINT WHITE (-8550 2475);
DISPLAY INVISIBLE (-8550 2475);
FORCEPROP 1 LAST WATTAGE 1/16W
J 0
(-8525 2250);
DISPLAY 0.489362 (-8525 2250);
PAINT SKYBLUE (-8525 2250);
DISPLAY INVISIBLE (-8525 2250);
FORCEPROP 1 LAST MATERIAL CHIP
J 0
(-8775 2300);
DISPLAY 0.489362 (-8775 2300);
PAINT SKYBLUE (-8775 2300);
DISPLAY INVISIBLE (-8775 2300);
FORCEPROP 1 LAST TOLERANCE 5%
J 2
(-8475 2300);
DISPLAY 0.489362 (-8475 2300);
PAINT SKYBLUE (-8475 2300);
DISPLAY INVISIBLE (-8475 2300);
FORCEPROP 1 LAST PART_NUMBER CS00002JB38
J 0
(-8700 2375);
DISPLAY 0.489362 (-8700 2375);
PAINT SKYBLUE (-8700 2375);
DISPLAY INVISIBLE (-8700 2375);
FORCEPROP 1 LAST PACK_TYPE 0402LF
J 0
(-8775 2250);
DISPLAY 0.489362 (-8775 2250);
PAINT SKYBLUE (-8775 2250);
DISPLAY INVISIBLE (-8775 2250);
FORCEPROP 2 LAST ROOM RST_CPU0_PLD_TO_DIMM
J 0
(-8625 2425);
DISPLAY 0.744681 (-8625 2425);
PAINT RED (-8625 2425);
DISPLAY INVISIBLE (-8625 2425);
FORCEADD VCC_CORE..1
(-8475 2650);
FORCEPROP 3 LASTPIN (-8475 2600) SIG_NAME P3V3_STBY\g
J 0
(-8465 2610);
DISPLAY 0.659574 (-8465 2610);
PAINT MONO (-8465 2610);
DISPLAY INVISIBLE (-8465 2610);
FORCEPROP 1 LAST HDL_POWER P3V3_STBY
J 1
(-8475 2700);
DISPLAY 0.489362 (-8475 2700);
PAINT GREEN (-8475 2700);
FORCEPROP 2 LAST CDS_LIB mstr_symbols
J 0
(-8475 2650);
DISPLAY INVISIBLE (-8475 2650);
FORCEPROP 1 LAST PATH I189
J 0
(-8425 2675);
DISPLAY 0.872340 (-8425 2675);
PAINT AQUA (-8425 2675);
DISPLAY INVISIBLE (-8425 2675);
FORCEPROP 0 LAST VOLTAGE 3.3
J 0
(-8750 2800);
DISPLAY 1.021277 (-8750 2800);
PAINT SKYBLUE (-8750 2800);
DISPLAY INVISIBLE (-8750 2800);
FORCEPROP 2 LAST ROOM PVCCINFAON_CPU0_CTRL
J 0
(-8475 2750);
DISPLAY 0.808511 (-8475 2750);
PAINT RED (-8475 2750);
DISPLAY INVISIBLE (-8475 2750);
FORCEADD TAP..1
R 2
(-7800 3875);
FORCEPROP 3 LASTPIN (-7750 3875) SIG_NAME M_D_CPU1_SA_CB<1>
J 0
(-7740 3885);
DISPLAY 0.659574 (-7740 3885);
PAINT MONO (-7740 3885);
DISPLAY INVISIBLE (-7740 3885);
FORCEPROP 1 LASTPIN (-7750 3875) BN 1
J 2
(-7738 3883);
DISPLAY 0.489362 (-7738 3883);
PAINT GREEN (-7738 3883);
FORCEPROP 2 LAST CDS_LIB mstr_standard
J 0
(-7800 3875);
DISPLAY 0.723404 (-7800 3875);
PAINT MONO (-7800 3875);
DISPLAY INVISIBLE (-7800 3875);
FORCEPROP 1 LAST BODY_TYPE PLUMBING
J 2
(-7800 3925);
DISPLAY 0.872340 (-7800 3925);
PAINT GREEN (-7800 3925);
DISPLAY INVISIBLE (-7800 3925);
FORCEPROP 1 LAST HDL_TAP TRUE
J 2
(-8125 3750);
DISPLAY 0.872340 (-8125 3750);
DISPLAY INVISIBLE (-8125 3750);
FORCEPROP 1 LAST PATH I19
J 2
(-7798 3875);
DISPLAY 0.872340 (-7798 3875);
PAINT GREEN (-7798 3875);
DISPLAY INVISIBLE (-7798 3875);
FORCEADD Q_RES..2
(-8475 2475);
FORCEPROP 1 LAST LOCATION R106
J 0
(-8430 2600);
DISPLAY 0.489362 (-8430 2600);
PAINT SKYBLUE (-8430 2600);
FORCEPROP 0 LAST $SEC 1
J 0
(-8425 2650);
DISPLAY 0.680851 (-8425 2650);
PAINT MONO (-8425 2650);
DISPLAY INVISIBLE (-8425 2650);
FORCEPROP 0 LAST CDS_SEC 1
J 0
(-8425 2650);
DISPLAY 1.021277 (-8425 2650);
DISPLAY INVISIBLE (-8425 2650);
FORCEPROP 1 LASTPIN (-8475 2575) $PN 1
J 0
(-8470 2537);
DISPLAY 0.489362 (-8470 2537);
PAINT MONO (-8470 2537);
FORCEPROP 1 LASTPIN (-8475 2375) $PN 2
J 0
(-8470 2385);
DISPLAY 0.489362 (-8470 2385);
PAINT MONO (-8470 2385);
FORCEPROP 1 LAST TOLERANCE 5%
J 0
(-8425 2525);
DISPLAY 0.489362 (-8425 2525);
PAINT SKYBLUE (-8425 2525);
FORCEPROP 1 LAST VALUE 1K
J 0
(-8430 2550);
DISPLAY 0.489362 (-8430 2550);
PAINT SKYBLUE (-8430 2550);
FORCEPROP 1 LAST PACK_TYPE 0402LF
J 0
(-8425 2425);
DISPLAY 0.489362 (-8425 2425);
PAINT SKYBLUE (-8425 2425);
FORCEPROP 1 LAST MATERIAL EMPTY
J 0
(-8425 2475);
DISPLAY 0.489362 (-8425 2475);
PAINT RED (-8425 2475);
FORCEPROP 1 LAST WATTAGE 1/16W
J 0
(-8425 2500);
DISPLAY 0.489362 (-8425 2500);
PAINT SKYBLUE (-8425 2500);
FORCEPROP 2 LAST BOM_COST MEM
J 0
(-8425 2650);
DISPLAY 0.808511 (-8425 2650);
DISPLAY INVISIBLE (-8425 2650);
FORCEPROP 2 LAST CDS_LIB pure_quanta
J 2
(-8475 2475);
DISPLAY INVISIBLE (-8475 2475);
FORCEPROP 1 LAST PATH I190
J 0
(-8425 2650);
DISPLAY 0.978723 (-8425 2650);
PAINT WHITE (-8425 2650);
DISPLAY INVISIBLE (-8425 2650);
FORCEPROP 1 LAST PART_NUMBER TMP_QCS21002JB34
J 0
(-8425 2450);
DISPLAY 0.489362 (-8425 2450);
PAINT SKYBLUE (-8425 2450);
DISPLAY INVISIBLE (-8425 2450);
FORCEPROP 2 LAST ROOM MEM_CH_A_CPU0_DIMM1
J 0
(-8425 2700);
DISPLAY 0.808511 (-8425 2700);
PAINT RED (-8425 2700);
DISPLAY INVISIBLE (-8425 2700);
FORCEADD TAP..1
(-3275 3875);
FORCEPROP 3 LASTPIN (-3325 3875) SIG_NAME M_D_CPU1_SA_DQS_DN<1>
J 0
(-3315 3885);
DISPLAY 0.659574 (-3315 3885);
PAINT MONO (-3315 3885);
DISPLAY INVISIBLE (-3315 3885);
FORCEPROP 1 LASTPIN (-3325 3875) BN 1
J 0
(-3337 3883);
DISPLAY 0.489362 (-3337 3883);
PAINT GREEN (-3337 3883);
FORCEPROP 2 LAST CDS_LIB mstr_standard
J 0
(-3275 3875);
DISPLAY 0.723404 (-3275 3875);
PAINT MONO (-3275 3875);
DISPLAY INVISIBLE (-3275 3875);
FORCEPROP 1 LAST BODY_TYPE PLUMBING
J 0
(-3275 3925);
DISPLAY 0.872340 (-3275 3925);
PAINT GREEN (-3275 3925);
DISPLAY INVISIBLE (-3275 3925);
FORCEPROP 1 LAST HDL_TAP TRUE
J 0
(-2950 3750);
DISPLAY 0.872340 (-2950 3750);
DISPLAY INVISIBLE (-2950 3750);
FORCEPROP 1 LAST PATH I191
J 0
(-3277 3875);
DISPLAY 0.872340 (-3277 3875);
PAINT GREEN (-3277 3875);
DISPLAY INVISIBLE (-3277 3875);
FORCEADD TAP..1
(-3275 3975);
FORCEPROP 3 LASTPIN (-3325 3975) SIG_NAME M_D_CPU1_SA_DQS_DN<2>
J 0
(-3315 3985);
DISPLAY 0.659574 (-3315 3985);
PAINT MONO (-3315 3985);
DISPLAY INVISIBLE (-3315 3985);
FORCEPROP 1 LASTPIN (-3325 3975) BN 2
J 0
(-3337 3983);
DISPLAY 0.489362 (-3337 3983);
PAINT GREEN (-3337 3983);
FORCEPROP 2 LAST CDS_LIB mstr_standard
J 0
(-3275 3975);
DISPLAY 0.723404 (-3275 3975);
PAINT MONO (-3275 3975);
DISPLAY INVISIBLE (-3275 3975);
FORCEPROP 1 LAST BODY_TYPE PLUMBING
J 0
(-3275 4025);
DISPLAY 0.872340 (-3275 4025);
PAINT GREEN (-3275 4025);
DISPLAY INVISIBLE (-3275 4025);
FORCEPROP 1 LAST HDL_TAP TRUE
J 0
(-2950 3850);
DISPLAY 0.872340 (-2950 3850);
DISPLAY INVISIBLE (-2950 3850);
FORCEPROP 1 LAST PATH I192
J 0
(-3277 3975);
DISPLAY 0.872340 (-3277 3975);
PAINT GREEN (-3277 3975);
DISPLAY INVISIBLE (-3277 3975);
FORCEADD TAP..1
(-3475 4025);
FORCEPROP 3 LASTPIN (-3525 4025) SIG_NAME M_D_CPU1_SA_DQS_DP<2>
J 0
(-3515 4035);
DISPLAY 0.659574 (-3515 4035);
PAINT MONO (-3515 4035);
DISPLAY INVISIBLE (-3515 4035);
FORCEPROP 1 LASTPIN (-3525 4025) BN 2
J 0
(-3537 4033);
DISPLAY 0.489362 (-3537 4033);
PAINT GREEN (-3537 4033);
FORCEPROP 2 LAST CDS_LIB mstr_standard
J 0
(-3475 4025);
DISPLAY 0.723404 (-3475 4025);
PAINT MONO (-3475 4025);
DISPLAY INVISIBLE (-3475 4025);
FORCEPROP 1 LAST BODY_TYPE PLUMBING
J 0
(-3475 4075);
DISPLAY 0.872340 (-3475 4075);
PAINT GREEN (-3475 4075);
DISPLAY INVISIBLE (-3475 4075);
FORCEPROP 1 LAST HDL_TAP TRUE
J 0
(-3150 3900);
DISPLAY 0.872340 (-3150 3900);
DISPLAY INVISIBLE (-3150 3900);
FORCEPROP 1 LAST PATH I193
J 0
(-3477 4025);
DISPLAY 0.872340 (-3477 4025);
PAINT GREEN (-3477 4025);
DISPLAY INVISIBLE (-3477 4025);
FORCEADD TAP..1
(-3475 4125);
FORCEPROP 3 LASTPIN (-3525 4125) SIG_NAME M_D_CPU1_SA_DQS_DP<3>
J 0
(-3515 4135);
DISPLAY 0.659574 (-3515 4135);
PAINT MONO (-3515 4135);
DISPLAY INVISIBLE (-3515 4135);
FORCEPROP 1 LASTPIN (-3525 4125) BN 3
J 0
(-3537 4133);
DISPLAY 0.489362 (-3537 4133);
PAINT GREEN (-3537 4133);
FORCEPROP 2 LAST CDS_LIB mstr_standard
J 0
(-3475 4125);
DISPLAY 0.723404 (-3475 4125);
PAINT MONO (-3475 4125);
DISPLAY INVISIBLE (-3475 4125);
FORCEPROP 1 LAST BODY_TYPE PLUMBING
J 0
(-3475 4175);
DISPLAY 0.872340 (-3475 4175);
PAINT GREEN (-3475 4175);
DISPLAY INVISIBLE (-3475 4175);
FORCEPROP 1 LAST HDL_TAP TRUE
J 0
(-3150 4000);
DISPLAY 0.872340 (-3150 4000);
DISPLAY INVISIBLE (-3150 4000);
FORCEPROP 1 LAST PATH I194
J 0
(-3477 4125);
DISPLAY 0.872340 (-3477 4125);
PAINT GREEN (-3477 4125);
DISPLAY INVISIBLE (-3477 4125);
FORCEADD OFFPAGE..2
(-2475 4775);
FORCEPROP 2 LAST $XR0 40 
J 0
(-2286 4775);
DISPLAY 0.638298 (-2286 4775);
PAINT MONO (-2286 4775);
FORCEPROP 1 LAST COMMENT_BODY TRUE
J 0
(-2520 4680);
DISPLAY 0.872340 (-2520 4680);
PAINT GREEN (-2520 4680);
DISPLAY INVISIBLE (-2520 4680);
FORCEPROP 1 LAST OFFPAGE TRUE
J 0
(-2150 4650);
DISPLAY 0.723404 (-2150 4650);
PAINT GREEN (-2150 4650);
DISPLAY INVISIBLE (-2150 4650);
FORCEPROP 2 LAST CDS_LIB mstr_standard
J 0
(-2475 4775);
DISPLAY 0.723404 (-2475 4775);
PAINT MONO (-2475 4775);
DISPLAY INVISIBLE (-2475 4775);
FORCEPROP 2 LAST PATH I196
J 0
(-2275 4825);
DISPLAY 0.680851 (-2275 4825);
DISPLAY INVISIBLE (-2275 4825);
FORCEADD OFFPAGE..2
(-2475 4725);
FORCEPROP 2 LAST $XR0 40 
J 0
(-2286 4725);
DISPLAY 0.638298 (-2286 4725);
PAINT MONO (-2286 4725);
FORCEPROP 1 LAST COMMENT_BODY TRUE
J 0
(-2520 4630);
DISPLAY 0.872340 (-2520 4630);
PAINT GREEN (-2520 4630);
DISPLAY INVISIBLE (-2520 4630);
FORCEPROP 1 LAST OFFPAGE TRUE
J 0
(-2150 4600);
DISPLAY 0.723404 (-2150 4600);
PAINT GREEN (-2150 4600);
DISPLAY INVISIBLE (-2150 4600);
FORCEPROP 2 LAST CDS_LIB mstr_standard
J 0
(-2475 4725);
DISPLAY 0.723404 (-2475 4725);
PAINT MONO (-2475 4725);
DISPLAY INVISIBLE (-2475 4725);
FORCEPROP 2 LAST PATH I197
J 0
(-2275 4775);
DISPLAY 0.680851 (-2275 4775);
DISPLAY INVISIBLE (-2275 4775);
FORCEADD TAP..1
(-3275 4675);
FORCEPROP 3 LASTPIN (-3325 4675) SIG_NAME M_D_CPU1_SA_DQS_DN<9>
J 0
(-3315 4685);
DISPLAY 0.659574 (-3315 4685);
PAINT MONO (-3315 4685);
DISPLAY INVISIBLE (-3315 4685);
FORCEPROP 1 LASTPIN (-3325 4675) BN 9
J 0
(-3337 4683);
DISPLAY 0.489362 (-3337 4683);
PAINT GREEN (-3337 4683);
FORCEPROP 2 LAST CDS_LIB mstr_standard
J 0
(-3275 4675);
DISPLAY 0.723404 (-3275 4675);
PAINT MONO (-3275 4675);
DISPLAY INVISIBLE (-3275 4675);
FORCEPROP 1 LAST BODY_TYPE PLUMBING
J 0
(-3275 4725);
DISPLAY 0.872340 (-3275 4725);
PAINT GREEN (-3275 4725);
DISPLAY INVISIBLE (-3275 4725);
FORCEPROP 1 LAST HDL_TAP TRUE
J 0
(-2950 4550);
DISPLAY 0.872340 (-2950 4550);
DISPLAY INVISIBLE (-2950 4550);
FORCEPROP 1 LAST PATH I198
J 0
(-3277 4675);
DISPLAY 0.872340 (-3277 4675);
PAINT GREEN (-3277 4675);
DISPLAY INVISIBLE (-3277 4675);
FORCEADD TAP..1
(-3275 4575);
FORCEPROP 3 LASTPIN (-3325 4575) SIG_NAME M_D_CPU1_SA_DQS_DN<8>
J 0
(-3315 4585);
DISPLAY 0.659574 (-3315 4585);
PAINT MONO (-3315 4585);
DISPLAY INVISIBLE (-3315 4585);
FORCEPROP 1 LASTPIN (-3325 4575) BN 8
J 0
(-3337 4583);
DISPLAY 0.489362 (-3337 4583);
PAINT GREEN (-3337 4583);
FORCEPROP 2 LAST CDS_LIB mstr_standard
J 0
(-3275 4575);
DISPLAY 0.723404 (-3275 4575);
PAINT MONO (-3275 4575);
DISPLAY INVISIBLE (-3275 4575);
FORCEPROP 1 LAST BODY_TYPE PLUMBING
J 0
(-3275 4625);
DISPLAY 0.872340 (-3275 4625);
PAINT GREEN (-3275 4625);
DISPLAY INVISIBLE (-3275 4625);
FORCEPROP 1 LAST HDL_TAP TRUE
J 0
(-2950 4450);
DISPLAY 0.872340 (-2950 4450);
DISPLAY INVISIBLE (-2950 4450);
FORCEPROP 1 LAST PATH I199
J 0
(-3277 4575);
DISPLAY 0.872340 (-3277 4575);
PAINT GREEN (-3277 4575);
DISPLAY INVISIBLE (-3277 4575);
FORCEADD OFFPAGE..5
(-8400 2175);
FORCEPROP 2 LAST $XR0 40 
J 0
(-8654 2175);
DISPLAY 0.638298 (-8654 2175);
PAINT MONO (-8654 2175);
FORCEPROP 2 LAST PATH I2
J 0
(-8600 2225);
DISPLAY 1.021277 (-8600 2225);
DISPLAY INVISIBLE (-8600 2225);
FORCEPROP 1 LAST COMMENT_BODY TRUE
J 0
(-8300 2100);
DISPLAY 0.872340 (-8300 2100);
PAINT GREEN (-8300 2100);
DISPLAY INVISIBLE (-8300 2100);
FORCEPROP 1 LAST OFFPAGE TRUE
J 0
(-8075 2050);
DISPLAY 0.872340 (-8075 2050);
PAINT GREEN (-8075 2050);
DISPLAY INVISIBLE (-8075 2050);
FORCEPROP 2 LAST CDS_LIB mstr_standard
J 0
(-8400 2175);
DISPLAY 0.808511 (-8400 2175);
DISPLAY INVISIBLE (-8400 2175);
FORCEADD TAP..1
R 2
(-7800 3825);
FORCEPROP 3 LASTPIN (-7750 3825) SIG_NAME M_D_CPU1_SA_CB<0>
J 0
(-7740 3835);
DISPLAY 0.659574 (-7740 3835);
PAINT MONO (-7740 3835);
DISPLAY INVISIBLE (-7740 3835);
FORCEPROP 1 LASTPIN (-7750 3825) BN 0
J 2
(-7738 3833);
DISPLAY 0.489362 (-7738 3833);
PAINT GREEN (-7738 3833);
FORCEPROP 2 LAST CDS_LIB mstr_standard
J 0
(-7800 3825);
DISPLAY 0.723404 (-7800 3825);
PAINT MONO (-7800 3825);
DISPLAY INVISIBLE (-7800 3825);
FORCEPROP 1 LAST BODY_TYPE PLUMBING
J 2
(-7800 3875);
DISPLAY 0.872340 (-7800 3875);
PAINT GREEN (-7800 3875);
DISPLAY INVISIBLE (-7800 3875);
FORCEPROP 1 LAST HDL_TAP TRUE
J 2
(-8125 3700);
DISPLAY 0.872340 (-8125 3700);
DISPLAY INVISIBLE (-8125 3700);
FORCEPROP 1 LAST PATH I20
J 2
(-7798 3825);
DISPLAY 0.872340 (-7798 3825);
PAINT GREEN (-7798 3825);
DISPLAY INVISIBLE (-7798 3825);
FORCEADD TAP..1
(-3275 4475);
FORCEPROP 3 LASTPIN (-3325 4475) SIG_NAME M_D_CPU1_SA_DQS_DN<7>
J 0
(-3315 4485);
DISPLAY 0.659574 (-3315 4485);
PAINT MONO (-3315 4485);
DISPLAY INVISIBLE (-3315 4485);
FORCEPROP 1 LASTPIN (-3325 4475) BN 7
J 0
(-3337 4483);
DISPLAY 0.489362 (-3337 4483);
PAINT GREEN (-3337 4483);
FORCEPROP 2 LAST CDS_LIB mstr_standard
J 0
(-3275 4475);
DISPLAY 0.723404 (-3275 4475);
PAINT MONO (-3275 4475);
DISPLAY INVISIBLE (-3275 4475);
FORCEPROP 1 LAST BODY_TYPE PLUMBING
J 0
(-3275 4525);
DISPLAY 0.872340 (-3275 4525);
PAINT GREEN (-3275 4525);
DISPLAY INVISIBLE (-3275 4525);
FORCEPROP 1 LAST HDL_TAP TRUE
J 0
(-2950 4350);
DISPLAY 0.872340 (-2950 4350);
DISPLAY INVISIBLE (-2950 4350);
FORCEPROP 1 LAST PATH I200
J 0
(-3277 4475);
DISPLAY 0.872340 (-3277 4475);
PAINT GREEN (-3277 4475);
DISPLAY INVISIBLE (-3277 4475);
FORCEADD TAP..1
(-3275 4375);
FORCEPROP 3 LASTPIN (-3325 4375) SIG_NAME M_D_CPU1_SA_DQS_DN<6>
J 0
(-3315 4385);
DISPLAY 0.659574 (-3315 4385);
PAINT MONO (-3315 4385);
DISPLAY INVISIBLE (-3315 4385);
FORCEPROP 1 LASTPIN (-3325 4375) BN 6
J 0
(-3337 4383);
DISPLAY 0.489362 (-3337 4383);
PAINT GREEN (-3337 4383);
FORCEPROP 2 LAST CDS_LIB mstr_standard
J 0
(-3275 4375);
DISPLAY 0.723404 (-3275 4375);
PAINT MONO (-3275 4375);
DISPLAY INVISIBLE (-3275 4375);
FORCEPROP 1 LAST BODY_TYPE PLUMBING
J 0
(-3275 4425);
DISPLAY 0.872340 (-3275 4425);
PAINT GREEN (-3275 4425);
DISPLAY INVISIBLE (-3275 4425);
FORCEPROP 1 LAST HDL_TAP TRUE
J 0
(-2950 4250);
DISPLAY 0.872340 (-2950 4250);
DISPLAY INVISIBLE (-2950 4250);
FORCEPROP 1 LAST PATH I201
J 0
(-3277 4375);
DISPLAY 0.872340 (-3277 4375);
PAINT GREEN (-3277 4375);
DISPLAY INVISIBLE (-3277 4375);
FORCEADD TAP..1
(-3475 4625);
FORCEPROP 3 LASTPIN (-3525 4625) SIG_NAME M_D_CPU1_SA_DQS_DP<8>
J 0
(-3515 4635);
DISPLAY 0.659574 (-3515 4635);
PAINT MONO (-3515 4635);
DISPLAY INVISIBLE (-3515 4635);
FORCEPROP 1 LASTPIN (-3525 4625) BN 8
J 0
(-3537 4633);
DISPLAY 0.489362 (-3537 4633);
PAINT GREEN (-3537 4633);
FORCEPROP 2 LAST CDS_LIB mstr_standard
J 0
(-3475 4625);
DISPLAY 0.723404 (-3475 4625);
PAINT MONO (-3475 4625);
DISPLAY INVISIBLE (-3475 4625);
FORCEPROP 1 LAST BODY_TYPE PLUMBING
J 0
(-3475 4675);
DISPLAY 0.872340 (-3475 4675);
PAINT GREEN (-3475 4675);
DISPLAY INVISIBLE (-3475 4675);
FORCEPROP 1 LAST HDL_TAP TRUE
J 0
(-3150 4500);
DISPLAY 0.872340 (-3150 4500);
DISPLAY INVISIBLE (-3150 4500);
FORCEPROP 1 LAST PATH I202
J 0
(-3477 4625);
DISPLAY 0.872340 (-3477 4625);
PAINT GREEN (-3477 4625);
DISPLAY INVISIBLE (-3477 4625);
FORCEADD TAP..1
(-3475 4725);
FORCEPROP 3 LASTPIN (-3525 4725) SIG_NAME M_D_CPU1_SA_DQS_DP<9>
J 0
(-3515 4735);
DISPLAY 0.659574 (-3515 4735);
PAINT MONO (-3515 4735);
DISPLAY INVISIBLE (-3515 4735);
FORCEPROP 1 LASTPIN (-3525 4725) BN 9
J 0
(-3537 4733);
DISPLAY 0.489362 (-3537 4733);
PAINT GREEN (-3537 4733);
FORCEPROP 2 LAST CDS_LIB mstr_standard
J 0
(-3475 4725);
DISPLAY 0.723404 (-3475 4725);
PAINT MONO (-3475 4725);
DISPLAY INVISIBLE (-3475 4725);
FORCEPROP 1 LAST BODY_TYPE PLUMBING
J 0
(-3475 4775);
DISPLAY 0.872340 (-3475 4775);
PAINT GREEN (-3475 4775);
DISPLAY INVISIBLE (-3475 4775);
FORCEPROP 1 LAST HDL_TAP TRUE
J 0
(-3150 4600);
DISPLAY 0.872340 (-3150 4600);
DISPLAY INVISIBLE (-3150 4600);
FORCEPROP 1 LAST PATH I203
J 0
(-3477 4725);
DISPLAY 0.872340 (-3477 4725);
PAINT GREEN (-3477 4725);
DISPLAY INVISIBLE (-3477 4725);
FORCEADD TAP..1
(-3475 4425);
FORCEPROP 3 LASTPIN (-3525 4425) SIG_NAME M_D_CPU1_SA_DQS_DP<6>
J 0
(-3515 4435);
DISPLAY 0.659574 (-3515 4435);
PAINT MONO (-3515 4435);
DISPLAY INVISIBLE (-3515 4435);
FORCEPROP 1 LASTPIN (-3525 4425) BN 6
J 0
(-3537 4433);
DISPLAY 0.489362 (-3537 4433);
PAINT GREEN (-3537 4433);
FORCEPROP 2 LAST CDS_LIB mstr_standard
J 0
(-3475 4425);
DISPLAY 0.723404 (-3475 4425);
PAINT MONO (-3475 4425);
DISPLAY INVISIBLE (-3475 4425);
FORCEPROP 1 LAST BODY_TYPE PLUMBING
J 0
(-3475 4475);
DISPLAY 0.872340 (-3475 4475);
PAINT GREEN (-3475 4475);
DISPLAY INVISIBLE (-3475 4475);
FORCEPROP 1 LAST HDL_TAP TRUE
J 0
(-3150 4300);
DISPLAY 0.872340 (-3150 4300);
DISPLAY INVISIBLE (-3150 4300);
FORCEPROP 1 LAST PATH I204
J 0
(-3477 4425);
DISPLAY 0.872340 (-3477 4425);
PAINT GREEN (-3477 4425);
DISPLAY INVISIBLE (-3477 4425);
FORCEADD TAP..1
(-3475 4525);
FORCEPROP 3 LASTPIN (-3525 4525) SIG_NAME M_D_CPU1_SA_DQS_DP<7>
J 0
(-3515 4535);
DISPLAY 0.659574 (-3515 4535);
PAINT MONO (-3515 4535);
DISPLAY INVISIBLE (-3515 4535);
FORCEPROP 1 LASTPIN (-3525 4525) BN 7
J 0
(-3537 4533);
DISPLAY 0.489362 (-3537 4533);
PAINT GREEN (-3537 4533);
FORCEPROP 2 LAST CDS_LIB mstr_standard
J 0
(-3475 4525);
DISPLAY 0.723404 (-3475 4525);
PAINT MONO (-3475 4525);
DISPLAY INVISIBLE (-3475 4525);
FORCEPROP 1 LAST BODY_TYPE PLUMBING
J 0
(-3475 4575);
DISPLAY 0.872340 (-3475 4575);
PAINT GREEN (-3475 4575);
DISPLAY INVISIBLE (-3475 4575);
FORCEPROP 1 LAST HDL_TAP TRUE
J 0
(-3150 4400);
DISPLAY 0.872340 (-3150 4400);
DISPLAY INVISIBLE (-3150 4400);
FORCEPROP 1 LAST PATH I205
J 0
(-3477 4525);
DISPLAY 0.872340 (-3477 4525);
PAINT GREEN (-3477 4525);
DISPLAY INVISIBLE (-3477 4525);
FORCEADD TAP..1
(-3475 4325);
FORCEPROP 3 LASTPIN (-3525 4325) SIG_NAME M_D_CPU1_SA_DQS_DP<5>
J 0
(-3515 4335);
DISPLAY 0.659574 (-3515 4335);
PAINT MONO (-3515 4335);
DISPLAY INVISIBLE (-3515 4335);
FORCEPROP 1 LASTPIN (-3525 4325) BN 5
J 0
(-3537 4333);
DISPLAY 0.489362 (-3537 4333);
PAINT GREEN (-3537 4333);
FORCEPROP 2 LAST CDS_LIB mstr_standard
J 0
(-3475 4325);
DISPLAY 0.723404 (-3475 4325);
PAINT MONO (-3475 4325);
DISPLAY INVISIBLE (-3475 4325);
FORCEPROP 1 LAST BODY_TYPE PLUMBING
J 0
(-3475 4375);
DISPLAY 0.872340 (-3475 4375);
PAINT GREEN (-3475 4375);
DISPLAY INVISIBLE (-3475 4375);
FORCEPROP 1 LAST HDL_TAP TRUE
J 0
(-3150 4200);
DISPLAY 0.872340 (-3150 4200);
DISPLAY INVISIBLE (-3150 4200);
FORCEPROP 1 LAST PATH I206
J 0
(-3477 4325);
DISPLAY 0.872340 (-3477 4325);
PAINT GREEN (-3477 4325);
DISPLAY INVISIBLE (-3477 4325);
FORCEADD TAP..1
(-3275 4275);
FORCEPROP 3 LASTPIN (-3325 4275) SIG_NAME M_D_CPU1_SA_DQS_DN<5>
J 0
(-3315 4285);
DISPLAY 0.659574 (-3315 4285);
PAINT MONO (-3315 4285);
DISPLAY INVISIBLE (-3315 4285);
FORCEPROP 1 LASTPIN (-3325 4275) BN 5
J 0
(-3337 4283);
DISPLAY 0.489362 (-3337 4283);
PAINT GREEN (-3337 4283);
FORCEPROP 2 LAST CDS_LIB mstr_standard
J 0
(-3275 4275);
DISPLAY 0.723404 (-3275 4275);
PAINT MONO (-3275 4275);
DISPLAY INVISIBLE (-3275 4275);
FORCEPROP 1 LAST BODY_TYPE PLUMBING
J 0
(-3275 4325);
DISPLAY 0.872340 (-3275 4325);
PAINT GREEN (-3275 4325);
DISPLAY INVISIBLE (-3275 4325);
FORCEPROP 1 LAST HDL_TAP TRUE
J 0
(-2950 4150);
DISPLAY 0.872340 (-2950 4150);
DISPLAY INVISIBLE (-2950 4150);
FORCEPROP 1 LAST PATH I207
J 0
(-3277 4275);
DISPLAY 0.872340 (-3277 4275);
PAINT GREEN (-3277 4275);
DISPLAY INVISIBLE (-3277 4275);
FORCEADD TAP..1
(-3275 4175);
FORCEPROP 3 LASTPIN (-3325 4175) SIG_NAME M_D_CPU1_SA_DQS_DN<4>
J 0
(-3315 4185);
DISPLAY 0.659574 (-3315 4185);
PAINT MONO (-3315 4185);
DISPLAY INVISIBLE (-3315 4185);
FORCEPROP 1 LASTPIN (-3325 4175) BN 4
J 0
(-3337 4183);
DISPLAY 0.489362 (-3337 4183);
PAINT GREEN (-3337 4183);
FORCEPROP 2 LAST CDS_LIB mstr_standard
J 0
(-3275 4175);
DISPLAY 0.723404 (-3275 4175);
PAINT MONO (-3275 4175);
DISPLAY INVISIBLE (-3275 4175);
FORCEPROP 1 LAST BODY_TYPE PLUMBING
J 0
(-3275 4225);
DISPLAY 0.872340 (-3275 4225);
PAINT GREEN (-3275 4225);
DISPLAY INVISIBLE (-3275 4225);
FORCEPROP 1 LAST HDL_TAP TRUE
J 0
(-2950 4050);
DISPLAY 0.872340 (-2950 4050);
DISPLAY INVISIBLE (-2950 4050);
FORCEPROP 1 LAST PATH I208
J 0
(-3277 4175);
DISPLAY 0.872340 (-3277 4175);
PAINT GREEN (-3277 4175);
DISPLAY INVISIBLE (-3277 4175);
FORCEADD TAP..1
(-3275 4075);
FORCEPROP 3 LASTPIN (-3325 4075) SIG_NAME M_D_CPU1_SA_DQS_DN<3>
J 0
(-3315 4085);
DISPLAY 0.659574 (-3315 4085);
PAINT MONO (-3315 4085);
DISPLAY INVISIBLE (-3315 4085);
FORCEPROP 1 LASTPIN (-3325 4075) BN 3
J 0
(-3337 4083);
DISPLAY 0.489362 (-3337 4083);
PAINT GREEN (-3337 4083);
FORCEPROP 2 LAST CDS_LIB mstr_standard
J 0
(-3275 4075);
DISPLAY 0.723404 (-3275 4075);
PAINT MONO (-3275 4075);
DISPLAY INVISIBLE (-3275 4075);
FORCEPROP 1 LAST BODY_TYPE PLUMBING
J 0
(-3275 4125);
DISPLAY 0.872340 (-3275 4125);
PAINT GREEN (-3275 4125);
DISPLAY INVISIBLE (-3275 4125);
FORCEPROP 1 LAST HDL_TAP TRUE
J 0
(-2950 3950);
DISPLAY 0.872340 (-2950 3950);
DISPLAY INVISIBLE (-2950 3950);
FORCEPROP 1 LAST PATH I209
J 0
(-3277 4075);
DISPLAY 0.872340 (-3277 4075);
PAINT GREEN (-3277 4075);
DISPLAY INVISIBLE (-3277 4075);
FORCEADD TAP..1
R 2
(-7800 3725);
FORCEPROP 3 LASTPIN (-7750 3725) SIG_NAME M_D_CPU1_SB_CB<7>
J 0
(-7740 3735);
DISPLAY 0.659574 (-7740 3735);
PAINT MONO (-7740 3735);
DISPLAY INVISIBLE (-7740 3735);
FORCEPROP 1 LASTPIN (-7750 3725) BN 7
J 2
(-7738 3733);
DISPLAY 0.489362 (-7738 3733);
PAINT GREEN (-7738 3733);
FORCEPROP 2 LAST CDS_LIB mstr_standard
J 0
(-7800 3725);
DISPLAY 0.723404 (-7800 3725);
PAINT MONO (-7800 3725);
DISPLAY INVISIBLE (-7800 3725);
FORCEPROP 1 LAST BODY_TYPE PLUMBING
J 2
(-7800 3775);
DISPLAY 0.872340 (-7800 3775);
PAINT GREEN (-7800 3775);
DISPLAY INVISIBLE (-7800 3775);
FORCEPROP 1 LAST HDL_TAP TRUE
J 2
(-8125 3600);
DISPLAY 0.872340 (-8125 3600);
DISPLAY INVISIBLE (-8125 3600);
FORCEPROP 1 LAST PATH I21
J 2
(-7798 3725);
DISPLAY 0.872340 (-7798 3725);
PAINT GREEN (-7798 3725);
DISPLAY INVISIBLE (-7798 3725);
FORCEADD TAP..1
(-3475 4225);
FORCEPROP 3 LASTPIN (-3525 4225) SIG_NAME M_D_CPU1_SA_DQS_DP<4>
J 0
(-3515 4235);
DISPLAY 0.659574 (-3515 4235);
PAINT MONO (-3515 4235);
DISPLAY INVISIBLE (-3515 4235);
FORCEPROP 1 LASTPIN (-3525 4225) BN 4
J 0
(-3537 4233);
DISPLAY 0.489362 (-3537 4233);
PAINT GREEN (-3537 4233);
FORCEPROP 2 LAST CDS_LIB mstr_standard
J 0
(-3475 4225);
DISPLAY 0.723404 (-3475 4225);
PAINT MONO (-3475 4225);
DISPLAY INVISIBLE (-3475 4225);
FORCEPROP 1 LAST BODY_TYPE PLUMBING
J 0
(-3475 4275);
DISPLAY 0.872340 (-3475 4275);
PAINT GREEN (-3475 4275);
DISPLAY INVISIBLE (-3475 4275);
FORCEPROP 1 LAST HDL_TAP TRUE
J 0
(-3150 4100);
DISPLAY 0.872340 (-3150 4100);
DISPLAY INVISIBLE (-3150 4100);
FORCEPROP 1 LAST PATH I210
J 0
(-3477 4225);
DISPLAY 0.872340 (-3477 4225);
PAINT GREEN (-3477 4225);
DISPLAY INVISIBLE (-3477 4225);
FORCEADD TAP..1
(-3475 3925);
FORCEPROP 3 LASTPIN (-3525 3925) SIG_NAME M_D_CPU1_SA_DQS_DP<1>
J 0
(-3515 3935);
DISPLAY 0.659574 (-3515 3935);
PAINT MONO (-3515 3935);
DISPLAY INVISIBLE (-3515 3935);
FORCEPROP 1 LASTPIN (-3525 3925) BN 1
J 0
(-3537 3933);
DISPLAY 0.489362 (-3537 3933);
PAINT GREEN (-3537 3933);
FORCEPROP 2 LAST CDS_LIB mstr_standard
J 0
(-3475 3925);
DISPLAY 0.723404 (-3475 3925);
PAINT MONO (-3475 3925);
DISPLAY INVISIBLE (-3475 3925);
FORCEPROP 1 LAST BODY_TYPE PLUMBING
J 0
(-3475 3975);
DISPLAY 0.872340 (-3475 3975);
PAINT GREEN (-3475 3975);
DISPLAY INVISIBLE (-3475 3975);
FORCEPROP 1 LAST HDL_TAP TRUE
J 0
(-3150 3800);
DISPLAY 0.872340 (-3150 3800);
DISPLAY INVISIBLE (-3150 3800);
FORCEPROP 1 LAST PATH I211
J 0
(-3477 3925);
DISPLAY 0.872340 (-3477 3925);
PAINT GREEN (-3477 3925);
DISPLAY INVISIBLE (-3477 3925);
FORCEADD TAP..1
(-3475 3825);
FORCEPROP 3 LASTPIN (-3525 3825) SIG_NAME M_D_CPU1_SA_DQS_DP<0>
J 0
(-3515 3835);
DISPLAY 0.659574 (-3515 3835);
PAINT MONO (-3515 3835);
DISPLAY INVISIBLE (-3515 3835);
FORCEPROP 1 LASTPIN (-3525 3825) BN 0
J 0
(-3537 3833);
DISPLAY 0.489362 (-3537 3833);
PAINT GREEN (-3537 3833);
FORCEPROP 2 LAST CDS_LIB mstr_standard
J 0
(-3475 3825);
DISPLAY 0.723404 (-3475 3825);
PAINT MONO (-3475 3825);
DISPLAY INVISIBLE (-3475 3825);
FORCEPROP 1 LAST BODY_TYPE PLUMBING
J 0
(-3475 3875);
DISPLAY 0.872340 (-3475 3875);
PAINT GREEN (-3475 3875);
DISPLAY INVISIBLE (-3475 3875);
FORCEPROP 1 LAST HDL_TAP TRUE
J 0
(-3150 3700);
DISPLAY 0.872340 (-3150 3700);
DISPLAY INVISIBLE (-3150 3700);
FORCEPROP 1 LAST PATH I212
J 0
(-3477 3825);
DISPLAY 0.872340 (-3477 3825);
PAINT GREEN (-3477 3825);
DISPLAY INVISIBLE (-3477 3825);
FORCEADD OFFPAGE..2
(-2475 3725);
FORCEPROP 2 LAST $XR0 40 
J 0
(-2286 3725);
DISPLAY 0.638298 (-2286 3725);
PAINT MONO (-2286 3725);
FORCEPROP 1 LAST COMMENT_BODY TRUE
J 0
(-2520 3630);
DISPLAY 0.872340 (-2520 3630);
PAINT GREEN (-2520 3630);
DISPLAY INVISIBLE (-2520 3630);
FORCEPROP 1 LAST OFFPAGE TRUE
J 0
(-2150 3600);
DISPLAY 0.723404 (-2150 3600);
PAINT GREEN (-2150 3600);
DISPLAY INVISIBLE (-2150 3600);
FORCEPROP 2 LAST CDS_LIB mstr_standard
J 0
(-2475 3725);
DISPLAY 0.723404 (-2475 3725);
PAINT MONO (-2475 3725);
DISPLAY INVISIBLE (-2475 3725);
FORCEPROP 2 LAST PATH I213
J 0
(-2275 3775);
DISPLAY 0.680851 (-2275 3775);
DISPLAY INVISIBLE (-2275 3775);
FORCEADD OFFPAGE..2
(-2475 3675);
FORCEPROP 2 LAST $XR0 40 
J 0
(-2286 3675);
DISPLAY 0.638298 (-2286 3675);
PAINT MONO (-2286 3675);
FORCEPROP 1 LAST COMMENT_BODY TRUE
J 0
(-2520 3580);
DISPLAY 0.872340 (-2520 3580);
PAINT GREEN (-2520 3580);
DISPLAY INVISIBLE (-2520 3580);
FORCEPROP 1 LAST OFFPAGE TRUE
J 0
(-2150 3550);
DISPLAY 0.723404 (-2150 3550);
PAINT GREEN (-2150 3550);
DISPLAY INVISIBLE (-2150 3550);
FORCEPROP 2 LAST CDS_LIB mstr_standard
J 0
(-2475 3675);
DISPLAY 0.723404 (-2475 3675);
PAINT MONO (-2475 3675);
DISPLAY INVISIBLE (-2475 3675);
FORCEPROP 2 LAST PATH I214
J 0
(-2275 3725);
DISPLAY 0.680851 (-2275 3725);
DISPLAY INVISIBLE (-2275 3725);
FORCEADD TAP..1
(-3275 3625);
FORCEPROP 3 LASTPIN (-3325 3625) SIG_NAME M_D_CPU1_SB_DQS_DN<9>
J 0
(-3315 3635);
DISPLAY 0.659574 (-3315 3635);
PAINT MONO (-3315 3635);
DISPLAY INVISIBLE (-3315 3635);
FORCEPROP 1 LASTPIN (-3325 3625) BN 9
J 0
(-3337 3633);
DISPLAY 0.489362 (-3337 3633);
PAINT GREEN (-3337 3633);
FORCEPROP 2 LAST CDS_LIB mstr_standard
J 0
(-3275 3625);
DISPLAY 0.723404 (-3275 3625);
PAINT MONO (-3275 3625);
DISPLAY INVISIBLE (-3275 3625);
FORCEPROP 1 LAST BODY_TYPE PLUMBING
J 0
(-3275 3675);
DISPLAY 0.872340 (-3275 3675);
PAINT GREEN (-3275 3675);
DISPLAY INVISIBLE (-3275 3675);
FORCEPROP 1 LAST HDL_TAP TRUE
J 0
(-2950 3500);
DISPLAY 0.872340 (-2950 3500);
DISPLAY INVISIBLE (-2950 3500);
FORCEPROP 1 LAST PATH I215
J 0
(-3277 3625);
DISPLAY 0.872340 (-3277 3625);
PAINT GREEN (-3277 3625);
DISPLAY INVISIBLE (-3277 3625);
FORCEADD TAP..1
(-3275 3775);
FORCEPROP 3 LASTPIN (-3325 3775) SIG_NAME M_D_CPU1_SA_DQS_DN<0>
J 0
(-3315 3785);
DISPLAY 0.659574 (-3315 3785);
PAINT MONO (-3315 3785);
DISPLAY INVISIBLE (-3315 3785);
FORCEPROP 1 LASTPIN (-3325 3775) BN 0
J 0
(-3337 3783);
DISPLAY 0.489362 (-3337 3783);
PAINT GREEN (-3337 3783);
FORCEPROP 2 LAST CDS_LIB mstr_standard
J 0
(-3275 3775);
DISPLAY 0.723404 (-3275 3775);
PAINT MONO (-3275 3775);
DISPLAY INVISIBLE (-3275 3775);
FORCEPROP 1 LAST BODY_TYPE PLUMBING
J 0
(-3275 3825);
DISPLAY 0.872340 (-3275 3825);
PAINT GREEN (-3275 3825);
DISPLAY INVISIBLE (-3275 3825);
FORCEPROP 1 LAST HDL_TAP TRUE
J 0
(-2950 3650);
DISPLAY 0.872340 (-2950 3650);
DISPLAY INVISIBLE (-2950 3650);
FORCEPROP 1 LAST PATH I216
J 0
(-3277 3775);
DISPLAY 0.872340 (-3277 3775);
PAINT GREEN (-3277 3775);
DISPLAY INVISIBLE (-3277 3775);
FORCEADD TAP..1
(-3275 3525);
FORCEPROP 3 LASTPIN (-3325 3525) SIG_NAME M_D_CPU1_SB_DQS_DN<8>
J 0
(-3315 3535);
DISPLAY 0.659574 (-3315 3535);
PAINT MONO (-3315 3535);
DISPLAY INVISIBLE (-3315 3535);
FORCEPROP 1 LASTPIN (-3325 3525) BN 8
J 0
(-3337 3533);
DISPLAY 0.489362 (-3337 3533);
PAINT GREEN (-3337 3533);
FORCEPROP 2 LAST CDS_LIB mstr_standard
J 0
(-3275 3525);
DISPLAY 0.723404 (-3275 3525);
PAINT MONO (-3275 3525);
DISPLAY INVISIBLE (-3275 3525);
FORCEPROP 1 LAST BODY_TYPE PLUMBING
J 0
(-3275 3575);
DISPLAY 0.872340 (-3275 3575);
PAINT GREEN (-3275 3575);
DISPLAY INVISIBLE (-3275 3575);
FORCEPROP 1 LAST HDL_TAP TRUE
J 0
(-2950 3400);
DISPLAY 0.872340 (-2950 3400);
DISPLAY INVISIBLE (-2950 3400);
FORCEPROP 1 LAST PATH I217
J 0
(-3277 3525);
DISPLAY 0.872340 (-3277 3525);
PAINT GREEN (-3277 3525);
DISPLAY INVISIBLE (-3277 3525);
FORCEADD TAP..1
(-3275 3425);
FORCEPROP 3 LASTPIN (-3325 3425) SIG_NAME M_D_CPU1_SB_DQS_DN<7>
J 0
(-3315 3435);
DISPLAY 0.659574 (-3315 3435);
PAINT MONO (-3315 3435);
DISPLAY INVISIBLE (-3315 3435);
FORCEPROP 1 LASTPIN (-3325 3425) BN 7
J 0
(-3337 3433);
DISPLAY 0.489362 (-3337 3433);
PAINT GREEN (-3337 3433);
FORCEPROP 2 LAST CDS_LIB mstr_standard
J 0
(-3275 3425);
DISPLAY 0.723404 (-3275 3425);
PAINT MONO (-3275 3425);
DISPLAY INVISIBLE (-3275 3425);
FORCEPROP 1 LAST BODY_TYPE PLUMBING
J 0
(-3275 3475);
DISPLAY 0.872340 (-3275 3475);
PAINT GREEN (-3275 3475);
DISPLAY INVISIBLE (-3275 3475);
FORCEPROP 1 LAST HDL_TAP TRUE
J 0
(-2950 3300);
DISPLAY 0.872340 (-2950 3300);
DISPLAY INVISIBLE (-2950 3300);
FORCEPROP 1 LAST PATH I218
J 0
(-3277 3425);
DISPLAY 0.872340 (-3277 3425);
PAINT GREEN (-3277 3425);
DISPLAY INVISIBLE (-3277 3425);
FORCEADD TAP..1
(-3275 3325);
FORCEPROP 3 LASTPIN (-3325 3325) SIG_NAME M_D_CPU1_SB_DQS_DN<6>
J 0
(-3315 3335);
DISPLAY 0.659574 (-3315 3335);
PAINT MONO (-3315 3335);
DISPLAY INVISIBLE (-3315 3335);
FORCEPROP 1 LASTPIN (-3325 3325) BN 6
J 0
(-3337 3333);
DISPLAY 0.489362 (-3337 3333);
PAINT GREEN (-3337 3333);
FORCEPROP 2 LAST CDS_LIB mstr_standard
J 0
(-3275 3325);
DISPLAY 0.723404 (-3275 3325);
PAINT MONO (-3275 3325);
DISPLAY INVISIBLE (-3275 3325);
FORCEPROP 1 LAST BODY_TYPE PLUMBING
J 0
(-3275 3375);
DISPLAY 0.872340 (-3275 3375);
PAINT GREEN (-3275 3375);
DISPLAY INVISIBLE (-3275 3375);
FORCEPROP 1 LAST HDL_TAP TRUE
J 0
(-2950 3200);
DISPLAY 0.872340 (-2950 3200);
DISPLAY INVISIBLE (-2950 3200);
FORCEPROP 1 LAST PATH I219
J 0
(-3277 3325);
DISPLAY 0.872340 (-3277 3325);
PAINT GREEN (-3277 3325);
DISPLAY INVISIBLE (-3277 3325);
FORCEADD TAP..1
R 2
(-7800 3925);
FORCEPROP 3 LASTPIN (-7750 3925) SIG_NAME M_D_CPU1_SA_CB<2>
J 0
(-7740 3935);
DISPLAY 0.659574 (-7740 3935);
PAINT MONO (-7740 3935);
DISPLAY INVISIBLE (-7740 3935);
FORCEPROP 1 LASTPIN (-7750 3925) BN 2
J 2
(-7738 3933);
DISPLAY 0.489362 (-7738 3933);
PAINT GREEN (-7738 3933);
FORCEPROP 2 LAST CDS_LIB mstr_standard
J 0
(-7800 3925);
DISPLAY 0.723404 (-7800 3925);
PAINT MONO (-7800 3925);
DISPLAY INVISIBLE (-7800 3925);
FORCEPROP 1 LAST BODY_TYPE PLUMBING
J 2
(-7800 3975);
DISPLAY 0.872340 (-7800 3975);
PAINT GREEN (-7800 3975);
DISPLAY INVISIBLE (-7800 3975);
FORCEPROP 1 LAST HDL_TAP TRUE
J 2
(-8125 3800);
DISPLAY 0.872340 (-8125 3800);
DISPLAY INVISIBLE (-8125 3800);
FORCEPROP 1 LAST PATH I22
J 2
(-7798 3925);
DISPLAY 0.872340 (-7798 3925);
PAINT GREEN (-7798 3925);
DISPLAY INVISIBLE (-7798 3925);
FORCEADD TAP..1
(-3475 3575);
FORCEPROP 3 LASTPIN (-3525 3575) SIG_NAME M_D_CPU1_SB_DQS_DP<8>
J 0
(-3515 3585);
DISPLAY 0.659574 (-3515 3585);
PAINT MONO (-3515 3585);
DISPLAY INVISIBLE (-3515 3585);
FORCEPROP 1 LASTPIN (-3525 3575) BN 8
J 0
(-3537 3583);
DISPLAY 0.489362 (-3537 3583);
PAINT GREEN (-3537 3583);
FORCEPROP 2 LAST CDS_LIB mstr_standard
J 0
(-3475 3575);
DISPLAY 0.723404 (-3475 3575);
PAINT MONO (-3475 3575);
DISPLAY INVISIBLE (-3475 3575);
FORCEPROP 1 LAST BODY_TYPE PLUMBING
J 0
(-3475 3625);
DISPLAY 0.872340 (-3475 3625);
PAINT GREEN (-3475 3625);
DISPLAY INVISIBLE (-3475 3625);
FORCEPROP 1 LAST HDL_TAP TRUE
J 0
(-3150 3450);
DISPLAY 0.872340 (-3150 3450);
DISPLAY INVISIBLE (-3150 3450);
FORCEPROP 1 LAST PATH I220
J 0
(-3477 3575);
DISPLAY 0.872340 (-3477 3575);
PAINT GREEN (-3477 3575);
DISPLAY INVISIBLE (-3477 3575);
FORCEADD TAP..1
(-3475 3675);
FORCEPROP 3 LASTPIN (-3525 3675) SIG_NAME M_D_CPU1_SB_DQS_DP<9>
J 0
(-3515 3685);
DISPLAY 0.659574 (-3515 3685);
PAINT MONO (-3515 3685);
DISPLAY INVISIBLE (-3515 3685);
FORCEPROP 1 LASTPIN (-3525 3675) BN 9
J 0
(-3537 3683);
DISPLAY 0.489362 (-3537 3683);
PAINT GREEN (-3537 3683);
FORCEPROP 2 LAST CDS_LIB mstr_standard
J 0
(-3475 3675);
DISPLAY 0.723404 (-3475 3675);
PAINT MONO (-3475 3675);
DISPLAY INVISIBLE (-3475 3675);
FORCEPROP 1 LAST BODY_TYPE PLUMBING
J 0
(-3475 3725);
DISPLAY 0.872340 (-3475 3725);
PAINT GREEN (-3475 3725);
DISPLAY INVISIBLE (-3475 3725);
FORCEPROP 1 LAST HDL_TAP TRUE
J 0
(-3150 3550);
DISPLAY 0.872340 (-3150 3550);
DISPLAY INVISIBLE (-3150 3550);
FORCEPROP 1 LAST PATH I221
J 0
(-3477 3675);
DISPLAY 0.872340 (-3477 3675);
PAINT GREEN (-3477 3675);
DISPLAY INVISIBLE (-3477 3675);
FORCEADD TAP..1
(-3475 3375);
FORCEPROP 3 LASTPIN (-3525 3375) SIG_NAME M_D_CPU1_SB_DQS_DP<6>
J 0
(-3515 3385);
DISPLAY 0.659574 (-3515 3385);
PAINT MONO (-3515 3385);
DISPLAY INVISIBLE (-3515 3385);
FORCEPROP 1 LASTPIN (-3525 3375) BN 6
J 0
(-3537 3383);
DISPLAY 0.489362 (-3537 3383);
PAINT GREEN (-3537 3383);
FORCEPROP 2 LAST CDS_LIB mstr_standard
J 0
(-3475 3375);
DISPLAY 0.723404 (-3475 3375);
PAINT MONO (-3475 3375);
DISPLAY INVISIBLE (-3475 3375);
FORCEPROP 1 LAST BODY_TYPE PLUMBING
J 0
(-3475 3425);
DISPLAY 0.872340 (-3475 3425);
PAINT GREEN (-3475 3425);
DISPLAY INVISIBLE (-3475 3425);
FORCEPROP 1 LAST HDL_TAP TRUE
J 0
(-3150 3250);
DISPLAY 0.872340 (-3150 3250);
DISPLAY INVISIBLE (-3150 3250);
FORCEPROP 1 LAST PATH I222
J 0
(-3477 3375);
DISPLAY 0.872340 (-3477 3375);
PAINT GREEN (-3477 3375);
DISPLAY INVISIBLE (-3477 3375);
FORCEADD TAP..1
(-3475 3475);
FORCEPROP 3 LASTPIN (-3525 3475) SIG_NAME M_D_CPU1_SB_DQS_DP<7>
J 0
(-3515 3485);
DISPLAY 0.659574 (-3515 3485);
PAINT MONO (-3515 3485);
DISPLAY INVISIBLE (-3515 3485);
FORCEPROP 1 LASTPIN (-3525 3475) BN 7
J 0
(-3537 3483);
DISPLAY 0.489362 (-3537 3483);
PAINT GREEN (-3537 3483);
FORCEPROP 2 LAST CDS_LIB mstr_standard
J 0
(-3475 3475);
DISPLAY 0.723404 (-3475 3475);
PAINT MONO (-3475 3475);
DISPLAY INVISIBLE (-3475 3475);
FORCEPROP 1 LAST BODY_TYPE PLUMBING
J 0
(-3475 3525);
DISPLAY 0.872340 (-3475 3525);
PAINT GREEN (-3475 3525);
DISPLAY INVISIBLE (-3475 3525);
FORCEPROP 1 LAST HDL_TAP TRUE
J 0
(-3150 3350);
DISPLAY 0.872340 (-3150 3350);
DISPLAY INVISIBLE (-3150 3350);
FORCEPROP 1 LAST PATH I223
J 0
(-3477 3475);
DISPLAY 0.872340 (-3477 3475);
PAINT GREEN (-3477 3475);
DISPLAY INVISIBLE (-3477 3475);
FORCEADD TAP..1
(-3275 3225);
FORCEPROP 3 LASTPIN (-3325 3225) SIG_NAME M_D_CPU1_SB_DQS_DN<5>
J 0
(-3315 3235);
DISPLAY 0.659574 (-3315 3235);
PAINT MONO (-3315 3235);
DISPLAY INVISIBLE (-3315 3235);
FORCEPROP 1 LASTPIN (-3325 3225) BN 5
J 0
(-3337 3233);
DISPLAY 0.489362 (-3337 3233);
PAINT GREEN (-3337 3233);
FORCEPROP 2 LAST CDS_LIB mstr_standard
J 0
(-3275 3225);
DISPLAY 0.723404 (-3275 3225);
PAINT MONO (-3275 3225);
DISPLAY INVISIBLE (-3275 3225);
FORCEPROP 1 LAST BODY_TYPE PLUMBING
J 0
(-3275 3275);
DISPLAY 0.872340 (-3275 3275);
PAINT GREEN (-3275 3275);
DISPLAY INVISIBLE (-3275 3275);
FORCEPROP 1 LAST HDL_TAP TRUE
J 0
(-2950 3100);
DISPLAY 0.872340 (-2950 3100);
DISPLAY INVISIBLE (-2950 3100);
FORCEPROP 1 LAST PATH I224
J 0
(-3277 3225);
DISPLAY 0.872340 (-3277 3225);
PAINT GREEN (-3277 3225);
DISPLAY INVISIBLE (-3277 3225);
FORCEADD TAP..1
(-3275 3125);
FORCEPROP 3 LASTPIN (-3325 3125) SIG_NAME M_D_CPU1_SB_DQS_DN<4>
J 0
(-3315 3135);
DISPLAY 0.659574 (-3315 3135);
PAINT MONO (-3315 3135);
DISPLAY INVISIBLE (-3315 3135);
FORCEPROP 1 LASTPIN (-3325 3125) BN 4
J 0
(-3337 3133);
DISPLAY 0.489362 (-3337 3133);
PAINT GREEN (-3337 3133);
FORCEPROP 2 LAST CDS_LIB mstr_standard
J 0
(-3275 3125);
DISPLAY 0.723404 (-3275 3125);
PAINT MONO (-3275 3125);
DISPLAY INVISIBLE (-3275 3125);
FORCEPROP 1 LAST BODY_TYPE PLUMBING
J 0
(-3275 3175);
DISPLAY 0.872340 (-3275 3175);
PAINT GREEN (-3275 3175);
DISPLAY INVISIBLE (-3275 3175);
FORCEPROP 1 LAST HDL_TAP TRUE
J 0
(-2950 3000);
DISPLAY 0.872340 (-2950 3000);
DISPLAY INVISIBLE (-2950 3000);
FORCEPROP 1 LAST PATH I225
J 0
(-3277 3125);
DISPLAY 0.872340 (-3277 3125);
PAINT GREEN (-3277 3125);
DISPLAY INVISIBLE (-3277 3125);
FORCEADD TAP..1
(-3275 3025);
FORCEPROP 3 LASTPIN (-3325 3025) SIG_NAME M_D_CPU1_SB_DQS_DN<3>
J 0
(-3315 3035);
DISPLAY 0.659574 (-3315 3035);
PAINT MONO (-3315 3035);
DISPLAY INVISIBLE (-3315 3035);
FORCEPROP 1 LASTPIN (-3325 3025) BN 3
J 0
(-3337 3033);
DISPLAY 0.489362 (-3337 3033);
PAINT GREEN (-3337 3033);
FORCEPROP 2 LAST CDS_LIB mstr_standard
J 0
(-3275 3025);
DISPLAY 0.723404 (-3275 3025);
PAINT MONO (-3275 3025);
DISPLAY INVISIBLE (-3275 3025);
FORCEPROP 1 LAST BODY_TYPE PLUMBING
J 0
(-3275 3075);
DISPLAY 0.872340 (-3275 3075);
PAINT GREEN (-3275 3075);
DISPLAY INVISIBLE (-3275 3075);
FORCEPROP 1 LAST HDL_TAP TRUE
J 0
(-2950 2900);
DISPLAY 0.872340 (-2950 2900);
DISPLAY INVISIBLE (-2950 2900);
FORCEPROP 1 LAST PATH I226
J 0
(-3277 3025);
DISPLAY 0.872340 (-3277 3025);
PAINT GREEN (-3277 3025);
DISPLAY INVISIBLE (-3277 3025);
FORCEADD TAP..1
(-3275 2925);
FORCEPROP 3 LASTPIN (-3325 2925) SIG_NAME M_D_CPU1_SB_DQS_DN<2>
J 0
(-3315 2935);
DISPLAY 0.659574 (-3315 2935);
PAINT MONO (-3315 2935);
DISPLAY INVISIBLE (-3315 2935);
FORCEPROP 1 LASTPIN (-3325 2925) BN 2
J 0
(-3337 2933);
DISPLAY 0.489362 (-3337 2933);
PAINT GREEN (-3337 2933);
FORCEPROP 2 LAST CDS_LIB mstr_standard
J 0
(-3275 2925);
DISPLAY 0.723404 (-3275 2925);
PAINT MONO (-3275 2925);
DISPLAY INVISIBLE (-3275 2925);
FORCEPROP 1 LAST BODY_TYPE PLUMBING
J 0
(-3275 2975);
DISPLAY 0.872340 (-3275 2975);
PAINT GREEN (-3275 2975);
DISPLAY INVISIBLE (-3275 2975);
FORCEPROP 1 LAST HDL_TAP TRUE
J 0
(-2950 2800);
DISPLAY 0.872340 (-2950 2800);
DISPLAY INVISIBLE (-2950 2800);
FORCEPROP 1 LAST PATH I227
J 0
(-3277 2925);
DISPLAY 0.872340 (-3277 2925);
PAINT GREEN (-3277 2925);
DISPLAY INVISIBLE (-3277 2925);
FORCEADD TAP..1
(-3275 2825);
FORCEPROP 3 LASTPIN (-3325 2825) SIG_NAME M_D_CPU1_SB_DQS_DN<1>
J 0
(-3315 2835);
DISPLAY 0.659574 (-3315 2835);
PAINT MONO (-3315 2835);
DISPLAY INVISIBLE (-3315 2835);
FORCEPROP 1 LASTPIN (-3325 2825) BN 1
J 0
(-3337 2833);
DISPLAY 0.489362 (-3337 2833);
PAINT GREEN (-3337 2833);
FORCEPROP 2 LAST CDS_LIB mstr_standard
J 0
(-3275 2825);
DISPLAY 0.723404 (-3275 2825);
PAINT MONO (-3275 2825);
DISPLAY INVISIBLE (-3275 2825);
FORCEPROP 1 LAST BODY_TYPE PLUMBING
J 0
(-3275 2875);
DISPLAY 0.872340 (-3275 2875);
PAINT GREEN (-3275 2875);
DISPLAY INVISIBLE (-3275 2875);
FORCEPROP 1 LAST HDL_TAP TRUE
J 0
(-2950 2700);
DISPLAY 0.872340 (-2950 2700);
DISPLAY INVISIBLE (-2950 2700);
FORCEPROP 1 LAST PATH I228
J 0
(-3277 2825);
DISPLAY 0.872340 (-3277 2825);
PAINT GREEN (-3277 2825);
DISPLAY INVISIBLE (-3277 2825);
FORCEADD TAP..1
(-3475 3075);
FORCEPROP 3 LASTPIN (-3525 3075) SIG_NAME M_D_CPU1_SB_DQS_DP<3>
J 0
(-3515 3085);
DISPLAY 0.659574 (-3515 3085);
PAINT MONO (-3515 3085);
DISPLAY INVISIBLE (-3515 3085);
FORCEPROP 1 LASTPIN (-3525 3075) BN 3
J 0
(-3537 3083);
DISPLAY 0.489362 (-3537 3083);
PAINT GREEN (-3537 3083);
FORCEPROP 2 LAST CDS_LIB mstr_standard
J 0
(-3475 3075);
DISPLAY 0.723404 (-3475 3075);
PAINT MONO (-3475 3075);
DISPLAY INVISIBLE (-3475 3075);
FORCEPROP 1 LAST BODY_TYPE PLUMBING
J 0
(-3475 3125);
DISPLAY 0.872340 (-3475 3125);
PAINT GREEN (-3475 3125);
DISPLAY INVISIBLE (-3475 3125);
FORCEPROP 1 LAST HDL_TAP TRUE
J 0
(-3150 2950);
DISPLAY 0.872340 (-3150 2950);
DISPLAY INVISIBLE (-3150 2950);
FORCEPROP 1 LAST PATH I229
J 0
(-3477 3075);
DISPLAY 0.872340 (-3477 3075);
PAINT GREEN (-3477 3075);
DISPLAY INVISIBLE (-3477 3075);
FORCEADD TAP..1
R 2
(-7800 3975);
FORCEPROP 3 LASTPIN (-7750 3975) SIG_NAME M_D_CPU1_SA_CB<3>
J 0
(-7740 3985);
DISPLAY 0.659574 (-7740 3985);
PAINT MONO (-7740 3985);
DISPLAY INVISIBLE (-7740 3985);
FORCEPROP 1 LASTPIN (-7750 3975) BN 3
J 2
(-7738 3983);
DISPLAY 0.489362 (-7738 3983);
PAINT GREEN (-7738 3983);
FORCEPROP 2 LAST CDS_LIB mstr_standard
J 0
(-7800 3975);
DISPLAY 0.723404 (-7800 3975);
PAINT MONO (-7800 3975);
DISPLAY INVISIBLE (-7800 3975);
FORCEPROP 1 LAST BODY_TYPE PLUMBING
J 2
(-7800 4025);
DISPLAY 0.872340 (-7800 4025);
PAINT GREEN (-7800 4025);
DISPLAY INVISIBLE (-7800 4025);
FORCEPROP 1 LAST HDL_TAP TRUE
J 2
(-8125 3850);
DISPLAY 0.872340 (-8125 3850);
DISPLAY INVISIBLE (-8125 3850);
FORCEPROP 1 LAST PATH I23
J 2
(-7798 3975);
DISPLAY 0.872340 (-7798 3975);
PAINT GREEN (-7798 3975);
DISPLAY INVISIBLE (-7798 3975);
FORCEADD TAP..1
(-3475 3275);
FORCEPROP 3 LASTPIN (-3525 3275) SIG_NAME M_D_CPU1_SB_DQS_DP<5>
J 0
(-3515 3285);
DISPLAY 0.659574 (-3515 3285);
PAINT MONO (-3515 3285);
DISPLAY INVISIBLE (-3515 3285);
FORCEPROP 1 LASTPIN (-3525 3275) BN 5
J 0
(-3537 3283);
DISPLAY 0.489362 (-3537 3283);
PAINT GREEN (-3537 3283);
FORCEPROP 2 LAST CDS_LIB mstr_standard
J 0
(-3475 3275);
DISPLAY 0.723404 (-3475 3275);
PAINT MONO (-3475 3275);
DISPLAY INVISIBLE (-3475 3275);
FORCEPROP 1 LAST BODY_TYPE PLUMBING
J 0
(-3475 3325);
DISPLAY 0.872340 (-3475 3325);
PAINT GREEN (-3475 3325);
DISPLAY INVISIBLE (-3475 3325);
FORCEPROP 1 LAST HDL_TAP TRUE
J 0
(-3150 3150);
DISPLAY 0.872340 (-3150 3150);
DISPLAY INVISIBLE (-3150 3150);
FORCEPROP 1 LAST PATH I230
J 0
(-3477 3275);
DISPLAY 0.872340 (-3477 3275);
PAINT GREEN (-3477 3275);
DISPLAY INVISIBLE (-3477 3275);
FORCEADD TAP..1
(-3475 3175);
FORCEPROP 3 LASTPIN (-3525 3175) SIG_NAME M_D_CPU1_SB_DQS_DP<4>
J 0
(-3515 3185);
DISPLAY 0.659574 (-3515 3185);
PAINT MONO (-3515 3185);
DISPLAY INVISIBLE (-3515 3185);
FORCEPROP 1 LASTPIN (-3525 3175) BN 4
J 0
(-3537 3183);
DISPLAY 0.489362 (-3537 3183);
PAINT GREEN (-3537 3183);
FORCEPROP 2 LAST CDS_LIB mstr_standard
J 0
(-3475 3175);
DISPLAY 0.723404 (-3475 3175);
PAINT MONO (-3475 3175);
DISPLAY INVISIBLE (-3475 3175);
FORCEPROP 1 LAST BODY_TYPE PLUMBING
J 0
(-3475 3225);
DISPLAY 0.872340 (-3475 3225);
PAINT GREEN (-3475 3225);
DISPLAY INVISIBLE (-3475 3225);
FORCEPROP 1 LAST HDL_TAP TRUE
J 0
(-3150 3050);
DISPLAY 0.872340 (-3150 3050);
DISPLAY INVISIBLE (-3150 3050);
FORCEPROP 1 LAST PATH I231
J 0
(-3477 3175);
DISPLAY 0.872340 (-3477 3175);
PAINT GREEN (-3477 3175);
DISPLAY INVISIBLE (-3477 3175);
FORCEADD TAP..1
(-3475 2775);
FORCEPROP 3 LASTPIN (-3525 2775) SIG_NAME M_D_CPU1_SB_DQS_DP<0>
J 0
(-3515 2785);
DISPLAY 0.659574 (-3515 2785);
PAINT MONO (-3515 2785);
DISPLAY INVISIBLE (-3515 2785);
FORCEPROP 1 LASTPIN (-3525 2775) BN 0
J 0
(-3537 2783);
DISPLAY 0.489362 (-3537 2783);
PAINT GREEN (-3537 2783);
FORCEPROP 2 LAST CDS_LIB mstr_standard
J 0
(-3475 2775);
DISPLAY 0.723404 (-3475 2775);
PAINT MONO (-3475 2775);
DISPLAY INVISIBLE (-3475 2775);
FORCEPROP 1 LAST BODY_TYPE PLUMBING
J 0
(-3475 2825);
DISPLAY 0.872340 (-3475 2825);
PAINT GREEN (-3475 2825);
DISPLAY INVISIBLE (-3475 2825);
FORCEPROP 1 LAST HDL_TAP TRUE
J 0
(-3150 2650);
DISPLAY 0.872340 (-3150 2650);
DISPLAY INVISIBLE (-3150 2650);
FORCEPROP 1 LAST PATH I232
J 0
(-3477 2775);
DISPLAY 0.872340 (-3477 2775);
PAINT GREEN (-3477 2775);
DISPLAY INVISIBLE (-3477 2775);
FORCEADD TAP..1
(-3475 2875);
FORCEPROP 3 LASTPIN (-3525 2875) SIG_NAME M_D_CPU1_SB_DQS_DP<1>
J 0
(-3515 2885);
DISPLAY 0.659574 (-3515 2885);
PAINT MONO (-3515 2885);
DISPLAY INVISIBLE (-3515 2885);
FORCEPROP 1 LASTPIN (-3525 2875) BN 1
J 0
(-3537 2883);
DISPLAY 0.489362 (-3537 2883);
PAINT GREEN (-3537 2883);
FORCEPROP 2 LAST CDS_LIB mstr_standard
J 0
(-3475 2875);
DISPLAY 0.723404 (-3475 2875);
PAINT MONO (-3475 2875);
DISPLAY INVISIBLE (-3475 2875);
FORCEPROP 1 LAST BODY_TYPE PLUMBING
J 0
(-3475 2925);
DISPLAY 0.872340 (-3475 2925);
PAINT GREEN (-3475 2925);
DISPLAY INVISIBLE (-3475 2925);
FORCEPROP 1 LAST HDL_TAP TRUE
J 0
(-3150 2750);
DISPLAY 0.872340 (-3150 2750);
DISPLAY INVISIBLE (-3150 2750);
FORCEPROP 1 LAST PATH I233
J 0
(-3477 2875);
DISPLAY 0.872340 (-3477 2875);
PAINT GREEN (-3477 2875);
DISPLAY INVISIBLE (-3477 2875);
FORCEADD TAP..1
(-3475 2975);
FORCEPROP 3 LASTPIN (-3525 2975) SIG_NAME M_D_CPU1_SB_DQS_DP<2>
J 0
(-3515 2985);
DISPLAY 0.659574 (-3515 2985);
PAINT MONO (-3515 2985);
DISPLAY INVISIBLE (-3515 2985);
FORCEPROP 1 LASTPIN (-3525 2975) BN 2
J 0
(-3537 2983);
DISPLAY 0.489362 (-3537 2983);
PAINT GREEN (-3537 2983);
FORCEPROP 2 LAST CDS_LIB mstr_standard
J 0
(-3475 2975);
DISPLAY 0.723404 (-3475 2975);
PAINT MONO (-3475 2975);
DISPLAY INVISIBLE (-3475 2975);
FORCEPROP 1 LAST BODY_TYPE PLUMBING
J 0
(-3475 3025);
DISPLAY 0.872340 (-3475 3025);
PAINT GREEN (-3475 3025);
DISPLAY INVISIBLE (-3475 3025);
FORCEPROP 1 LAST HDL_TAP TRUE
J 0
(-3150 2850);
DISPLAY 0.872340 (-3150 2850);
DISPLAY INVISIBLE (-3150 2850);
FORCEPROP 1 LAST PATH I234
J 0
(-3477 2975);
DISPLAY 0.872340 (-3477 2975);
PAINT GREEN (-3477 2975);
DISPLAY INVISIBLE (-3477 2975);
FORCEADD TAP..1
(-3275 2725);
FORCEPROP 3 LASTPIN (-3325 2725) SIG_NAME M_D_CPU1_SB_DQS_DN<0>
J 0
(-3315 2735);
DISPLAY 0.659574 (-3315 2735);
PAINT MONO (-3315 2735);
DISPLAY INVISIBLE (-3315 2735);
FORCEPROP 1 LASTPIN (-3325 2725) BN 0
J 0
(-3337 2733);
DISPLAY 0.489362 (-3337 2733);
PAINT GREEN (-3337 2733);
FORCEPROP 2 LAST CDS_LIB mstr_standard
J 0
(-3275 2725);
DISPLAY 0.723404 (-3275 2725);
PAINT MONO (-3275 2725);
DISPLAY INVISIBLE (-3275 2725);
FORCEPROP 1 LAST BODY_TYPE PLUMBING
J 0
(-3275 2775);
DISPLAY 0.872340 (-3275 2775);
PAINT GREEN (-3275 2775);
DISPLAY INVISIBLE (-3275 2775);
FORCEPROP 1 LAST HDL_TAP TRUE
J 0
(-2950 2600);
DISPLAY 0.872340 (-2950 2600);
DISPLAY INVISIBLE (-2950 2600);
FORCEPROP 1 LAST PATH I235
J 0
(-3277 2725);
DISPLAY 0.872340 (-3277 2725);
PAINT GREEN (-3277 2725);
DISPLAY INVISIBLE (-3277 2725);
FORCEADD SCONN288_DDR506112002KQ..2
(-4425 3725);
FORCEPROP 1 LAST LOCATION J30
J 0
(-5025 5050);
DISPLAY 0.468085 (-5025 5050);
PAINT SKYBLUE (-5025 5050);
FORCEPROP 0 LAST $SEC 2
J 0
(-4875 5200);
DISPLAY 0.680851 (-4875 5200);
PAINT MONO (-4875 5200);
DISPLAY INVISIBLE (-4875 5200);
FORCEPROP 0 LAST CDS_SEC 2
J 0
(-4875 5200);
DISPLAY 1.021277 (-4875 5200);
DISPLAY INVISIBLE (-4875 5200);
FORCEPROP 0 LASTPIN (-3675 3775) $PN 12
J 0
(-3665 3785);
DISPLAY 0.680851 (-3665 3785);
PAINT MONO (-3665 3785);
FORCEPROP 0 LASTPIN (-3675 3825) $PN 11
J 0
(-3665 3835);
DISPLAY 0.680851 (-3665 3835);
PAINT MONO (-3665 3835);
FORCEPROP 0 LASTPIN (-3675 2725) $PN 105
J 0
(-3665 2735);
DISPLAY 0.680851 (-3665 2735);
PAINT MONO (-3665 2735);
FORCEPROP 0 LASTPIN (-3675 2775) $PN 104
J 0
(-3665 2785);
DISPLAY 0.680851 (-3665 2785);
PAINT MONO (-3665 2785);
FORCEPROP 0 LASTPIN (-3675 3875) $PN 23
J 0
(-3665 3885);
DISPLAY 0.680851 (-3665 3885);
PAINT MONO (-3665 3885);
FORCEPROP 0 LASTPIN (-3675 3925) $PN 22
J 0
(-3665 3935);
DISPLAY 0.680851 (-3665 3935);
PAINT MONO (-3665 3935);
FORCEPROP 0 LASTPIN (-3675 2825) $PN 116
J 0
(-3665 2835);
DISPLAY 0.680851 (-3665 2835);
PAINT MONO (-3665 2835);
FORCEPROP 0 LASTPIN (-3675 2875) $PN 115
J 0
(-3665 2885);
DISPLAY 0.680851 (-3665 2885);
PAINT MONO (-3665 2885);
FORCEPROP 0 LASTPIN (-3675 3975) $PN 34
J 0
(-3665 3985);
DISPLAY 0.680851 (-3665 3985);
PAINT MONO (-3665 3985);
FORCEPROP 0 LASTPIN (-3675 4025) $PN 33
J 0
(-3665 4035);
DISPLAY 0.680851 (-3665 4035);
PAINT MONO (-3665 4035);
FORCEPROP 0 LASTPIN (-3675 2925) $PN 127
J 0
(-3665 2935);
DISPLAY 0.680851 (-3665 2935);
PAINT MONO (-3665 2935);
FORCEPROP 0 LASTPIN (-3675 2975) $PN 126
J 0
(-3665 2985);
DISPLAY 0.680851 (-3665 2985);
PAINT MONO (-3665 2985);
FORCEPROP 0 LASTPIN (-3675 4075) $PN 45
J 0
(-3665 4085);
DISPLAY 0.680851 (-3665 4085);
PAINT MONO (-3665 4085);
FORCEPROP 0 LASTPIN (-3675 4125) $PN 44
J 0
(-3665 4135);
DISPLAY 0.680851 (-3665 4135);
PAINT MONO (-3665 4135);
FORCEPROP 0 LASTPIN (-3675 3025) $PN 138
J 0
(-3665 3035);
DISPLAY 0.680851 (-3665 3035);
PAINT MONO (-3665 3035);
FORCEPROP 0 LASTPIN (-3675 3075) $PN 137
J 0
(-3665 3085);
DISPLAY 0.680851 (-3665 3085);
PAINT MONO (-3665 3085);
FORCEPROP 0 LASTPIN (-3675 4175) $PN 56
J 0
(-3665 4185);
DISPLAY 0.680851 (-3665 4185);
PAINT MONO (-3665 4185);
FORCEPROP 0 LASTPIN (-3675 4225) $PN 55
J 0
(-3665 4235);
DISPLAY 0.680851 (-3665 4235);
PAINT MONO (-3665 4235);
FORCEPROP 0 LASTPIN (-3675 3125) $PN 238
J 0
(-3665 3135);
DISPLAY 0.680851 (-3665 3135);
PAINT MONO (-3665 3135);
FORCEPROP 0 LASTPIN (-3675 3175) $PN 239
J 0
(-3665 3185);
DISPLAY 0.680851 (-3665 3185);
PAINT MONO (-3665 3185);
FORCEPROP 0 LASTPIN (-3675 4275) $PN 156
J 0
(-3665 4285);
DISPLAY 0.680851 (-3665 4285);
PAINT MONO (-3665 4285);
FORCEPROP 0 LASTPIN (-3675 4325) $PN 157
J 0
(-3665 4335);
DISPLAY 0.680851 (-3665 4335);
PAINT MONO (-3665 4335);
FORCEPROP 0 LASTPIN (-3675 3225) $PN 249
J 0
(-3665 3235);
DISPLAY 0.680851 (-3665 3235);
PAINT MONO (-3665 3235);
FORCEPROP 0 LASTPIN (-3675 3275) $PN 250
J 0
(-3665 3285);
DISPLAY 0.680851 (-3665 3285);
PAINT MONO (-3665 3285);
FORCEPROP 0 LASTPIN (-3675 4375) $PN 167
J 0
(-3665 4385);
DISPLAY 0.680851 (-3665 4385);
PAINT MONO (-3665 4385);
FORCEPROP 0 LASTPIN (-3675 4425) $PN 168
J 0
(-3665 4435);
DISPLAY 0.680851 (-3665 4435);
PAINT MONO (-3665 4435);
FORCEPROP 0 LASTPIN (-3675 3325) $PN 260
J 0
(-3665 3335);
DISPLAY 0.680851 (-3665 3335);
PAINT MONO (-3665 3335);
FORCEPROP 0 LASTPIN (-3675 3375) $PN 261
J 0
(-3665 3385);
DISPLAY 0.680851 (-3665 3385);
PAINT MONO (-3665 3385);
FORCEPROP 0 LASTPIN (-3675 4475) $PN 178
J 0
(-3665 4485);
DISPLAY 0.680851 (-3665 4485);
PAINT MONO (-3665 4485);
FORCEPROP 0 LASTPIN (-3675 4525) $PN 179
J 0
(-3665 4535);
DISPLAY 0.680851 (-3665 4535);
PAINT MONO (-3665 4535);
FORCEPROP 0 LASTPIN (-3675 3425) $PN 271
J 0
(-3665 3435);
DISPLAY 0.680851 (-3665 3435);
PAINT MONO (-3665 3435);
FORCEPROP 0 LASTPIN (-3675 3475) $PN 272
J 0
(-3665 3485);
DISPLAY 0.680851 (-3665 3485);
PAINT MONO (-3665 3485);
FORCEPROP 0 LASTPIN (-3675 4575) $PN 189
J 0
(-3665 4585);
DISPLAY 0.680851 (-3665 4585);
PAINT MONO (-3665 4585);
FORCEPROP 0 LASTPIN (-3675 4625) $PN 190
J 0
(-3665 4635);
DISPLAY 0.680851 (-3665 4635);
PAINT MONO (-3665 4635);
FORCEPROP 0 LASTPIN (-3675 3525) $PN 282
J 0
(-3665 3535);
DISPLAY 0.680851 (-3665 3535);
PAINT MONO (-3665 3535);
FORCEPROP 0 LASTPIN (-3675 3575) $PN 283
J 0
(-3665 3585);
DISPLAY 0.680851 (-3665 3585);
PAINT MONO (-3665 3585);
FORCEPROP 0 LASTPIN (-3675 4675) $PN 200
J 0
(-3665 4685);
DISPLAY 0.680851 (-3665 4685);
PAINT MONO (-3665 4685);
FORCEPROP 0 LASTPIN (-3675 4725) $PN 201
J 0
(-3665 4735);
DISPLAY 0.680851 (-3665 4735);
PAINT MONO (-3665 4735);
FORCEPROP 0 LASTPIN (-3675 3625) $PN 94
J 0
(-3665 3635);
DISPLAY 0.680851 (-3665 3635);
PAINT MONO (-3665 3635);
FORCEPROP 0 LASTPIN (-3675 3675) $PN 93
J 0
(-3665 3685);
DISPLAY 0.680851 (-3665 3685);
PAINT MONO (-3665 3685);
FORCEPROP 2 LAST PART_TYPE SMLF
J 0
(-4875 5150);
DISPLAY 1.021277 (-4875 5150);
FORCEPROP 2 LAST VALUE SCONN288_DDR506112002KQ
J 0
(-4875 5100);
DISPLAY 0.489362 (-4875 5100);
PAINT SKYBLUE (-4875 5100);
FORCEPROP 1 LAST MATERIAL IO
J 0
(-5025 4900);
DISPLAY 0.468085 (-5025 4900);
PAINT SKYBLUE (-5025 4900);
FORCEPROP 1 LAST PART_NUMBER DFHST8FS479
J 0
(-5025 4975);
DISPLAY 0.468085 (-5025 4975);
PAINT SKYBLUE (-5025 4975);
FORCEPROP 1 LAST CDS_LMAN_SYM_OUTLINE -600,1150,600,-1150
J 0
(-4425 3725);
DISPLAY 0.468085 (-4425 3725);
PAINT GREEN (-4425 3725);
DISPLAY INVISIBLE (-4425 3725);
FORCEPROP 1 LAST PATH I236
J 0
(-4425 3725);
DISPLAY 0.723404 (-4425 3725);
PAINT GREEN (-4425 3725);
DISPLAY INVISIBLE (-4425 3725);
FORCEPROP 1 LAST NEEDS_NO_SIZE TRUE
J 0
(-4425 3725);
DISPLAY 0.723404 (-4425 3725);
PAINT GREEN (-4425 3725);
DISPLAY INVISIBLE (-4425 3725);
FORCEPROP 2 LAST CDS_LIB pure_quanta
J 0
(-4425 3725);
DISPLAY INVISIBLE (-4425 3725);
FORCEADD GND..1
(-2900 5450);
FORCEPROP 3 LASTPIN (-2900 5500) SIG_NAME GND\g
J 0
(-2890 5510);
DISPLAY 0.659574 (-2890 5510);
PAINT MONO (-2890 5510);
DISPLAY INVISIBLE (-2890 5510);
FORCEPROP 2 LAST CDS_LIB pure_quanta_power
J 0
(-2900 5450);
DISPLAY INVISIBLE (-2900 5450);
FORCEPROP 2 LAST BOM_COST MEM
J 0
(-2875 5575);
DISPLAY 0.659574 (-2875 5575);
DISPLAY INVISIBLE (-2875 5575);
FORCEPROP 1 LAST SIZE 1B
J 0
(-2825 5400);
DISPLAY 0.723404 (-2825 5400);
PAINT GREEN (-2825 5400);
DISPLAY INVISIBLE (-2825 5400);
FORCEPROP 1 LAST PATH I237
J 0
(-2825 5450);
DISPLAY 0.872340 (-2825 5450);
PAINT AQUA (-2825 5450);
DISPLAY INVISIBLE (-2825 5450);
FORCEPROP 2 LAST ROOM MEM_EFGH_DECOUPLING_CAPS
J 0
(-2875 5525);
DISPLAY 0.659574 (-2875 5525);
PAINT RED (-2875 5525);
DISPLAY INVISIBLE (-2875 5525);
FORCEPROP 1 LAST HDL_POWER GND
J 0
(-2900 5600);
DISPLAY 0.723404 (-2900 5600);
PAINT GREEN (-2900 5600);
DISPLAY INVISIBLE (-2900 5600);
FORCEADD Q_CAP..1
R 2
(-2900 5800);
FORCEPROP 1 LAST LOCATION C181
J 2
(-2950 5900);
DISPLAY 0.489362 (-2950 5900);
PAINT SKYBLUE (-2950 5900);
FORCEPROP 0 LAST $SEC 1
J 0
(-2950 5950);
DISPLAY 0.680851 (-2950 5950);
PAINT MONO (-2950 5950);
DISPLAY INVISIBLE (-2950 5950);
FORCEPROP 0 LAST CDS_SEC 1
J 0
(-2950 5950);
DISPLAY 0.680851 (-2950 5950);
DISPLAY INVISIBLE (-2950 5950);
FORCEPROP 1 LASTPIN (-2900 5900) $PN 1
J 2
(-2910 5880);
DISPLAY 0.489362 (-2910 5880);
PAINT MONO (-2910 5880);
FORCEPROP 1 LASTPIN (-2900 5700) $PN 2
J 2
(-2910 5680);
DISPLAY 0.489362 (-2910 5680);
PAINT MONO (-2910 5680);
FORCEPROP 1 LAST MATERIAL X6S
J 2
(-2950 5700);
DISPLAY 0.489362 (-2950 5700);
PAINT SKYBLUE (-2950 5700);
FORCEPROP 1 LAST TOLERANCE 10%
J 2
(-2950 5750);
DISPLAY 0.489362 (-2950 5750);
PAINT SKYBLUE (-2950 5750);
FORCEPROP 1 LAST VALUE 10UF
J 2
(-2950 5850);
DISPLAY 0.489362 (-2950 5850);
PAINT SKYBLUE (-2950 5850);
FORCEPROP 1 LAST PART_NUMBER CH6104KEA00
J 2
(-2950 5650);
DISPLAY 0.489362 (-2950 5650);
PAINT SKYBLUE (-2950 5650);
FORCEPROP 1 LAST VOLTAGE 25V
J 2
(-2950 5800);
DISPLAY 0.489362 (-2950 5800);
PAINT SKYBLUE (-2950 5800);
FORCEPROP 1 LAST PACK_TYPE C0805
J 2
(-2950 5600);
DISPLAY 0.489362 (-2950 5600);
PAINT SKYBLUE (-2950 5600);
FORCEPROP 0 LAST BOM_COST MEM
J 2
(-2955 5945);
DISPLAY 0.595745 (-2955 5945);
PAINT MONO (-2955 5945);
DISPLAY INVISIBLE (-2955 5945);
FORCEPROP 2 LAST CDS_LIB pure_quanta
J 0
(-2900 5800);
DISPLAY INVISIBLE (-2900 5800);
FORCEPROP 1 LAST PATH I238
J 2
(-2950 5950);
DISPLAY 0.978723 (-2950 5950);
PAINT WHITE (-2950 5950);
DISPLAY INVISIBLE (-2950 5950);
FORCEPROP 0 LAST ROOM MEM_CH_A_CPU0_DIMM1
J 2
(-2955 5945);
DISPLAY 0.595745 (-2955 5945);
PAINT RED (-2955 5945);
DISPLAY INVISIBLE (-2955 5945);
FORCEADD Q_CAP..1
R 2
(-2325 5800);
FORCEPROP 1 LAST LOCATION C182
J 2
(-2375 5900);
DISPLAY 0.489362 (-2375 5900);
PAINT SKYBLUE (-2375 5900);
FORCEPROP 0 LAST $SEC 1
J 0
(-2375 5950);
DISPLAY 0.680851 (-2375 5950);
PAINT MONO (-2375 5950);
DISPLAY INVISIBLE (-2375 5950);
FORCEPROP 0 LAST CDS_SEC 1
J 0
(-2375 5950);
DISPLAY 0.680851 (-2375 5950);
DISPLAY INVISIBLE (-2375 5950);
FORCEPROP 1 LASTPIN (-2325 5900) $PN 1
J 2
(-2335 5880);
DISPLAY 0.489362 (-2335 5880);
PAINT MONO (-2335 5880);
FORCEPROP 1 LASTPIN (-2325 5700) $PN 2
J 2
(-2335 5680);
DISPLAY 0.489362 (-2335 5680);
PAINT MONO (-2335 5680);
FORCEPROP 1 LAST MATERIAL X6S
J 2
(-2375 5700);
DISPLAY 0.489362 (-2375 5700);
PAINT SKYBLUE (-2375 5700);
FORCEPROP 1 LAST TOLERANCE 10%
J 2
(-2375 5750);
DISPLAY 0.489362 (-2375 5750);
PAINT SKYBLUE (-2375 5750);
FORCEPROP 1 LAST VALUE 10UF
J 2
(-2375 5850);
DISPLAY 0.489362 (-2375 5850);
PAINT SKYBLUE (-2375 5850);
FORCEPROP 1 LAST VOLTAGE 25V
J 2
(-2375 5800);
DISPLAY 0.489362 (-2375 5800);
PAINT SKYBLUE (-2375 5800);
FORCEPROP 1 LAST PACK_TYPE C0805
J 2
(-2375 5600);
DISPLAY 0.489362 (-2375 5600);
PAINT SKYBLUE (-2375 5600);
FORCEPROP 1 LAST PART_NUMBER CH6104KEA00
J 2
(-2375 5650);
DISPLAY 0.489362 (-2375 5650);
PAINT SKYBLUE (-2375 5650);
FORCEPROP 0 LAST BOM_COST MEM
J 2
(-2380 5945);
DISPLAY 0.595745 (-2380 5945);
PAINT MONO (-2380 5945);
DISPLAY INVISIBLE (-2380 5945);
FORCEPROP 2 LAST CDS_LIB pure_quanta
J 0
(-2325 5800);
DISPLAY INVISIBLE (-2325 5800);
FORCEPROP 1 LAST PATH I239
J 2
(-2375 5950);
DISPLAY 0.978723 (-2375 5950);
PAINT WHITE (-2375 5950);
DISPLAY INVISIBLE (-2375 5950);
FORCEPROP 0 LAST ROOM MEM_CH_A_CPU0_DIMM1
J 2
(-2380 5945);
DISPLAY 0.595745 (-2380 5945);
PAINT RED (-2380 5945);
DISPLAY INVISIBLE (-2380 5945);
FORCEADD TAP..1
R 2
(-7800 4025);
FORCEPROP 3 LASTPIN (-7750 4025) SIG_NAME M_D_CPU1_SA_CB<4>
J 0
(-7740 4035);
DISPLAY 0.659574 (-7740 4035);
PAINT MONO (-7740 4035);
DISPLAY INVISIBLE (-7740 4035);
FORCEPROP 1 LASTPIN (-7750 4025) BN 4
J 2
(-7738 4033);
DISPLAY 0.489362 (-7738 4033);
PAINT GREEN (-7738 4033);
FORCEPROP 2 LAST CDS_LIB mstr_standard
J 0
(-7800 4025);
DISPLAY 0.723404 (-7800 4025);
PAINT MONO (-7800 4025);
DISPLAY INVISIBLE (-7800 4025);
FORCEPROP 1 LAST BODY_TYPE PLUMBING
J 2
(-7800 4075);
DISPLAY 0.872340 (-7800 4075);
PAINT GREEN (-7800 4075);
DISPLAY INVISIBLE (-7800 4075);
FORCEPROP 1 LAST HDL_TAP TRUE
J 2
(-8125 3900);
DISPLAY 0.872340 (-8125 3900);
DISPLAY INVISIBLE (-8125 3900);
FORCEPROP 1 LAST PATH I24
J 2
(-7798 4025);
DISPLAY 0.872340 (-7798 4025);
PAINT GREEN (-7798 4025);
DISPLAY INVISIBLE (-7798 4025);
FORCEADD UNIVERSAL_POWER..1
(-2900 6125);
FORCEPROP 3 LASTPIN (-2900 6075) SIG_NAME P12V_MEM_2\g
J 0
(-2890 6085);
DISPLAY 0.659574 (-2890 6085);
PAINT MONO (-2890 6085);
DISPLAY INVISIBLE (-2890 6085);
FORCEPROP 1 LAST HDL_POWER P12V_MEM_2
J 1
(-2900 6175);
DISPLAY 0.489362 (-2900 6175);
PAINT GREEN (-2900 6175);
FORCEPROP 2 LAST CDS_LIB pure_quanta_power
J 0
(-2900 6125);
DISPLAY INVISIBLE (-2900 6125);
FORCEPROP 1 LAST PATH I240
J 0
(-2850 6150);
DISPLAY 0.872340 (-2850 6150);
PAINT AQUA (-2850 6150);
DISPLAY INVISIBLE (-2850 6150);
FORCEADD OFFPAGE..1
(-8425 2875);
FORCEPROP 2 LAST $XR5 102 
J 0
(-9187 2875);
DISPLAY 0.638298 (-9187 2875);
PAINT MONO (-9187 2875);
FORCEPROP 2 LAST $XR4 101 
J 0
(-9067 2875);
DISPLAY 0.638298 (-9067 2875);
PAINT MONO (-9067 2875);
FORCEPROP 2 LAST $XR3 99 
J 0
(-8947 2875);
DISPLAY 0.638298 (-8947 2875);
PAINT MONO (-8947 2875);
FORCEPROP 2 LAST $XR2 98 
J 0
(-8857 2875);
DISPLAY 0.638298 (-8857 2875);
PAINT MONO (-8857 2875);
FORCEPROP 2 LAST $XR1 97 
J 0
(-8767 2875);
DISPLAY 0.638298 (-8767 2875);
PAINT MONO (-8767 2875);
FORCEPROP 2 LAST $XR0 136 
J 0
(-8677 2875);
DISPLAY 0.638298 (-8677 2875);
PAINT MONO (-8677 2875);
FORCEPROP 2 LAST PATH I241
J 0
(-8700 2925);
DISPLAY 0.680851 (-8700 2925);
DISPLAY INVISIBLE (-8700 2925);
FORCEPROP 1 LAST COMMENT_BODY TRUE
J 0
(-8300 2775);
DISPLAY 0.872340 (-8300 2775);
PAINT GREEN (-8300 2775);
DISPLAY INVISIBLE (-8300 2775);
FORCEPROP 1 LAST OFFPAGE TRUE
J 0
(-8100 2750);
DISPLAY 0.872340 (-8100 2750);
PAINT GREEN (-8100 2750);
DISPLAY INVISIBLE (-8100 2750);
FORCEPROP 2 LAST CDS_LIB mstr_standard
J 0
(-8425 2875);
DISPLAY 0.808511 (-8425 2875);
DISPLAY INVISIBLE (-8425 2875);
FORCEADD Q_RES..1
(-7850 2875);
FORCEPROP 1 LAST $LOCATION R1583
J 0
(-7900 2900);
DISPLAY 0.510638 (-7900 2900);
PAINT SKYBLUE (-7900 2900);
FORCEPROP 0 LAST CDS_LOCATION R1583
J 0
(-7900 2975);
DISPLAY 0.680851 (-7900 2975);
DISPLAY INVISIBLE (-7900 2975);
FORCEPROP 0 LAST $SEC 1
J 0
(-7900 2975);
DISPLAY 0.680851 (-7900 2975);
PAINT MONO (-7900 2975);
DISPLAY INVISIBLE (-7900 2975);
FORCEPROP 0 LAST CDS_SEC 1
J 0
(-7900 2975);
DISPLAY 0.680851 (-7900 2975);
DISPLAY INVISIBLE (-7900 2975);
FORCEPROP 1 LASTPIN (-7950 2875) $PN 1
J 0
(-7938 2887);
DISPLAY 0.787234 (-7938 2887);
PAINT MONO (-7938 2887);
FORCEPROP 1 LASTPIN (-7750 2875) $PN 2
J 0
(-7788 2887);
DISPLAY 0.787234 (-7788 2887);
PAINT MONO (-7788 2887);
FORCEPROP 1 LAST VALUE 49.9
J 2
(-7700 2925);
DISPLAY 0.510638 (-7700 2925);
PAINT SKYBLUE (-7700 2925);
FORCEPROP 2 LAST CDS_LIB pure_quanta
J 0
(-7850 2875);
DISPLAY INVISIBLE (-7850 2875);
FORCEPROP 1 LAST PATH I242
J 0
(-7900 3025);
DISPLAY 0.978723 (-7900 3025);
PAINT WHITE (-7900 3025);
DISPLAY INVISIBLE (-7900 3025);
FORCEPROP 1 LAST MATERIAL CHIP
J 0
(-7850 2725);
DISPLAY 0.978723 (-7850 2725);
DISPLAY INVISIBLE (-7850 2725);
FORCEPROP 1 LAST PACK_TYPE 0402LF
J 0
(-7600 2725);
DISPLAY 0.978723 (-7600 2725);
DISPLAY INVISIBLE (-7600 2725);
FORCEPROP 1 LAST WATTAGE 1/16W
J 2
(-7875 2725);
DISPLAY 0.978723 (-7875 2725);
DISPLAY INVISIBLE (-7875 2725);
FORCEPROP 1 LAST TOLERANCE 1%
J 0
(-7850 2775);
DISPLAY 0.978723 (-7850 2775);
DISPLAY INVISIBLE (-7850 2775);
FORCEPROP 1 LAST PART_NUMBER CS04992FB07
J 0
(-7900 2975);
DISPLAY 0.978723 (-7900 2975);
DISPLAY INVISIBLE (-7900 2975);
FORCEADD TAP..1
R 2
(-7800 4125);
FORCEPROP 3 LASTPIN (-7750 4125) SIG_NAME M_D_CPU1_SA_CB<6>
J 0
(-7740 4135);
DISPLAY 0.659574 (-7740 4135);
PAINT MONO (-7740 4135);
DISPLAY INVISIBLE (-7740 4135);
FORCEPROP 1 LASTPIN (-7750 4125) BN 6
J 2
(-7738 4133);
DISPLAY 0.489362 (-7738 4133);
PAINT GREEN (-7738 4133);
FORCEPROP 2 LAST CDS_LIB mstr_standard
J 0
(-7800 4125);
DISPLAY 0.723404 (-7800 4125);
PAINT MONO (-7800 4125);
DISPLAY INVISIBLE (-7800 4125);
FORCEPROP 1 LAST BODY_TYPE PLUMBING
J 2
(-7800 4175);
DISPLAY 0.872340 (-7800 4175);
PAINT GREEN (-7800 4175);
DISPLAY INVISIBLE (-7800 4175);
FORCEPROP 1 LAST HDL_TAP TRUE
J 2
(-8125 4000);
DISPLAY 0.872340 (-8125 4000);
DISPLAY INVISIBLE (-8125 4000);
FORCEPROP 1 LAST PATH I25
J 2
(-7798 4125);
DISPLAY 0.872340 (-7798 4125);
PAINT GREEN (-7798 4125);
DISPLAY INVISIBLE (-7798 4125);
FORCEADD TAP..1
R 2
(-7800 4075);
FORCEPROP 3 LASTPIN (-7750 4075) SIG_NAME M_D_CPU1_SA_CB<5>
J 0
(-7740 4085);
DISPLAY 0.659574 (-7740 4085);
PAINT MONO (-7740 4085);
DISPLAY INVISIBLE (-7740 4085);
FORCEPROP 1 LASTPIN (-7750 4075) BN 5
J 2
(-7738 4083);
DISPLAY 0.489362 (-7738 4083);
PAINT GREEN (-7738 4083);
FORCEPROP 2 LAST CDS_LIB mstr_standard
J 0
(-7800 4075);
DISPLAY 0.723404 (-7800 4075);
PAINT MONO (-7800 4075);
DISPLAY INVISIBLE (-7800 4075);
FORCEPROP 1 LAST BODY_TYPE PLUMBING
J 2
(-7800 4125);
DISPLAY 0.872340 (-7800 4125);
PAINT GREEN (-7800 4125);
DISPLAY INVISIBLE (-7800 4125);
FORCEPROP 1 LAST HDL_TAP TRUE
J 2
(-8125 3950);
DISPLAY 0.872340 (-8125 3950);
DISPLAY INVISIBLE (-8125 3950);
FORCEPROP 1 LAST PATH I26
J 2
(-7798 4075);
DISPLAY 0.872340 (-7798 4075);
PAINT GREEN (-7798 4075);
DISPLAY INVISIBLE (-7798 4075);
FORCEADD TAP..1
R 2
(-7800 4175);
FORCEPROP 3 LASTPIN (-7750 4175) SIG_NAME M_D_CPU1_SA_CB<7>
J 0
(-7740 4185);
DISPLAY 0.659574 (-7740 4185);
PAINT MONO (-7740 4185);
DISPLAY INVISIBLE (-7740 4185);
FORCEPROP 1 LASTPIN (-7750 4175) BN 7
J 2
(-7738 4183);
DISPLAY 0.489362 (-7738 4183);
PAINT GREEN (-7738 4183);
FORCEPROP 2 LAST CDS_LIB mstr_standard
J 0
(-7800 4175);
DISPLAY 0.723404 (-7800 4175);
PAINT MONO (-7800 4175);
DISPLAY INVISIBLE (-7800 4175);
FORCEPROP 1 LAST BODY_TYPE PLUMBING
J 2
(-7800 4225);
DISPLAY 0.872340 (-7800 4225);
PAINT GREEN (-7800 4225);
DISPLAY INVISIBLE (-7800 4225);
FORCEPROP 1 LAST HDL_TAP TRUE
J 2
(-8125 4050);
DISPLAY 0.872340 (-8125 4050);
DISPLAY INVISIBLE (-8125 4050);
FORCEPROP 1 LAST PATH I27
J 2
(-7798 4175);
DISPLAY 0.872340 (-7798 4175);
PAINT GREEN (-7798 4175);
DISPLAY INVISIBLE (-7798 4175);
FORCEADD OFFPAGE..1
(-8400 4325);
FORCEPROP 2 LAST $XR0 40 
J 0
(-8621 4325);
DISPLAY 0.638298 (-8621 4325);
PAINT MONO (-8621 4325);
FORCEPROP 2 LAST PATH I28
J 0
(-8650 4375);
DISPLAY 1.021277 (-8650 4375);
DISPLAY INVISIBLE (-8650 4375);
FORCEPROP 1 LAST COMMENT_BODY TRUE
J 0
(-8275 4225);
DISPLAY 0.872340 (-8275 4225);
PAINT GREEN (-8275 4225);
DISPLAY INVISIBLE (-8275 4225);
FORCEPROP 1 LAST OFFPAGE TRUE
J 0
(-8075 4200);
DISPLAY 0.872340 (-8075 4200);
PAINT GREEN (-8075 4200);
DISPLAY INVISIBLE (-8075 4200);
FORCEPROP 2 LAST CDS_LIB mstr_standard
J 0
(-8400 4325);
DISPLAY 0.723404 (-8400 4325);
PAINT MONO (-8400 4325);
DISPLAY INVISIBLE (-8400 4325);
FORCEADD OFFPAGE..1
(-8400 4275);
FORCEPROP 2 LAST $XR0 40 
J 0
(-8621 4275);
DISPLAY 0.638298 (-8621 4275);
PAINT MONO (-8621 4275);
FORCEPROP 2 LAST PATH I29
J 0
(-8650 4325);
DISPLAY 1.021277 (-8650 4325);
DISPLAY INVISIBLE (-8650 4325);
FORCEPROP 1 LAST COMMENT_BODY TRUE
J 0
(-8275 4175);
DISPLAY 0.872340 (-8275 4175);
PAINT GREEN (-8275 4175);
DISPLAY INVISIBLE (-8275 4175);
FORCEPROP 1 LAST OFFPAGE TRUE
J 0
(-8075 4150);
DISPLAY 0.872340 (-8075 4150);
PAINT GREEN (-8075 4150);
DISPLAY INVISIBLE (-8075 4150);
FORCEPROP 2 LAST CDS_LIB mstr_standard
J 0
(-8400 4275);
DISPLAY 0.808511 (-8400 4275);
DISPLAY INVISIBLE (-8400 4275);
FORCEADD OFFPAGE..1
(-8400 4425);
FORCEPROP 2 LAST $XR0 40 
J 0
(-8621 4425);
DISPLAY 0.638298 (-8621 4425);
PAINT MONO (-8621 4425);
FORCEPROP 2 LAST PATH I30
J 0
(-8650 4475);
DISPLAY 1.021277 (-8650 4475);
DISPLAY INVISIBLE (-8650 4475);
FORCEPROP 1 LAST COMMENT_BODY TRUE
J 0
(-8275 4325);
DISPLAY 0.872340 (-8275 4325);
PAINT GREEN (-8275 4325);
DISPLAY INVISIBLE (-8275 4325);
FORCEPROP 1 LAST OFFPAGE TRUE
J 0
(-8075 4300);
DISPLAY 0.872340 (-8075 4300);
PAINT GREEN (-8075 4300);
DISPLAY INVISIBLE (-8075 4300);
FORCEPROP 2 LAST CDS_LIB mstr_standard
J 0
(-8400 4425);
DISPLAY 0.808511 (-8400 4425);
DISPLAY INVISIBLE (-8400 4425);
FORCEADD OFFPAGE..1
(-8400 4475);
FORCEPROP 2 LAST $XR0 40 
J 0
(-8621 4475);
DISPLAY 0.638298 (-8621 4475);
PAINT MONO (-8621 4475);
FORCEPROP 2 LAST PATH I31
J 0
(-8650 4525);
DISPLAY 1.021277 (-8650 4525);
DISPLAY INVISIBLE (-8650 4525);
FORCEPROP 1 LAST COMMENT_BODY TRUE
J 0
(-8275 4375);
DISPLAY 0.872340 (-8275 4375);
PAINT GREEN (-8275 4375);
DISPLAY INVISIBLE (-8275 4375);
FORCEPROP 1 LAST OFFPAGE TRUE
J 0
(-8075 4350);
DISPLAY 0.872340 (-8075 4350);
PAINT GREEN (-8075 4350);
DISPLAY INVISIBLE (-8075 4350);
FORCEPROP 2 LAST CDS_LIB mstr_standard
J 0
(-8400 4475);
DISPLAY 0.723404 (-8400 4475);
PAINT MONO (-8400 4475);
DISPLAY INVISIBLE (-8400 4475);
FORCEADD OFFPAGE..1
(-8400 4625);
FORCEPROP 2 LAST $XR0 40 
J 0
(-8621 4625);
DISPLAY 0.638298 (-8621 4625);
PAINT MONO (-8621 4625);
FORCEPROP 2 LAST PATH I32
J 0
(-8650 4675);
DISPLAY 1.021277 (-8650 4675);
DISPLAY INVISIBLE (-8650 4675);
FORCEPROP 1 LAST COMMENT_BODY TRUE
J 0
(-8275 4525);
DISPLAY 0.872340 (-8275 4525);
PAINT GREEN (-8275 4525);
DISPLAY INVISIBLE (-8275 4525);
FORCEPROP 1 LAST OFFPAGE TRUE
J 0
(-8075 4500);
DISPLAY 0.872340 (-8075 4500);
PAINT GREEN (-8075 4500);
DISPLAY INVISIBLE (-8075 4500);
FORCEPROP 2 LAST CDS_LIB mstr_standard
J 0
(-8400 4625);
DISPLAY 0.723404 (-8400 4625);
PAINT MONO (-8400 4625);
DISPLAY INVISIBLE (-8400 4625);
FORCEADD OFFPAGE..1
(-8400 4575);
FORCEPROP 2 LAST $XR0 40 
J 0
(-8621 4575);
DISPLAY 0.638298 (-8621 4575);
PAINT MONO (-8621 4575);
FORCEPROP 2 LAST PATH I33
J 0
(-8650 4625);
DISPLAY 1.021277 (-8650 4625);
DISPLAY INVISIBLE (-8650 4625);
FORCEPROP 1 LAST COMMENT_BODY TRUE
J 0
(-8275 4475);
DISPLAY 0.872340 (-8275 4475);
PAINT GREEN (-8275 4475);
DISPLAY INVISIBLE (-8275 4475);
FORCEPROP 1 LAST OFFPAGE TRUE
J 0
(-8075 4450);
DISPLAY 0.872340 (-8075 4450);
PAINT GREEN (-8075 4450);
DISPLAY INVISIBLE (-8075 4450);
FORCEPROP 2 LAST CDS_LIB mstr_standard
J 0
(-8400 4575);
DISPLAY 0.808511 (-8400 4575);
DISPLAY INVISIBLE (-8400 4575);
FORCEADD OFFPAGE..1
(-8400 4725);
FORCEPROP 2 LAST $XR0 40 
J 0
(-8621 4725);
DISPLAY 0.638298 (-8621 4725);
PAINT MONO (-8621 4725);
FORCEPROP 2 LAST PATH I34
J 0
(-8650 4775);
DISPLAY 1.021277 (-8650 4775);
DISPLAY INVISIBLE (-8650 4775);
FORCEPROP 1 LAST COMMENT_BODY TRUE
J 0
(-8275 4625);
DISPLAY 0.872340 (-8275 4625);
PAINT GREEN (-8275 4625);
DISPLAY INVISIBLE (-8275 4625);
FORCEPROP 1 LAST OFFPAGE TRUE
J 0
(-8075 4600);
DISPLAY 0.872340 (-8075 4600);
PAINT GREEN (-8075 4600);
DISPLAY INVISIBLE (-8075 4600);
FORCEPROP 2 LAST CDS_LIB mstr_standard
J 0
(-8400 4725);
DISPLAY 0.808511 (-8400 4725);
DISPLAY INVISIBLE (-8400 4725);
FORCEADD OFFPAGE..1
(-8400 4775);
FORCEPROP 2 LAST $XR0 40 
J 0
(-8621 4775);
DISPLAY 0.638298 (-8621 4775);
PAINT MONO (-8621 4775);
FORCEPROP 2 LAST PATH I35
J 0
(-8650 4825);
DISPLAY 1.021277 (-8650 4825);
DISPLAY INVISIBLE (-8650 4825);
FORCEPROP 1 LAST COMMENT_BODY TRUE
J 0
(-8275 4675);
DISPLAY 0.872340 (-8275 4675);
PAINT GREEN (-8275 4675);
DISPLAY INVISIBLE (-8275 4675);
FORCEPROP 1 LAST OFFPAGE TRUE
J 0
(-8075 4650);
DISPLAY 0.872340 (-8075 4650);
PAINT GREEN (-8075 4650);
DISPLAY INVISIBLE (-8075 4650);
FORCEPROP 2 LAST CDS_LIB mstr_standard
J 0
(-8400 4775);
DISPLAY 0.723404 (-8400 4775);
PAINT MONO (-8400 4775);
DISPLAY INVISIBLE (-8400 4775);
FORCEADD OFFPAGE..1
(-8400 5225);
FORCEPROP 2 LAST $XR0 40 
J 0
(-8621 5225);
DISPLAY 0.638298 (-8621 5225);
PAINT MONO (-8621 5225);
FORCEPROP 2 LAST PATH I36
J 0
(-8650 5275);
DISPLAY 1.021277 (-8650 5275);
DISPLAY INVISIBLE (-8650 5275);
FORCEPROP 1 LAST COMMENT_BODY TRUE
J 0
(-8275 5125);
DISPLAY 0.872340 (-8275 5125);
PAINT GREEN (-8275 5125);
DISPLAY INVISIBLE (-8275 5125);
FORCEPROP 1 LAST OFFPAGE TRUE
J 0
(-8075 5100);
DISPLAY 0.872340 (-8075 5100);
PAINT GREEN (-8075 5100);
DISPLAY INVISIBLE (-8075 5100);
FORCEPROP 2 LAST CDS_LIB mstr_standard
J 0
(-8400 5225);
DISPLAY 0.723404 (-8400 5225);
PAINT MONO (-8400 5225);
DISPLAY INVISIBLE (-8400 5225);
FORCEADD TAP..1
R 2
(-7800 4875);
FORCEPROP 3 LASTPIN (-7750 4875) SIG_NAME M_D_CPU1_SB_CA<0>
J 0
(-7740 4885);
DISPLAY 0.659574 (-7740 4885);
PAINT MONO (-7740 4885);
DISPLAY INVISIBLE (-7740 4885);
FORCEPROP 1 LASTPIN (-7750 4875) BN 0
J 2
(-7738 4883);
DISPLAY 0.489362 (-7738 4883);
PAINT GREEN (-7738 4883);
FORCEPROP 2 LAST CDS_LIB mstr_standard
J 0
(-7800 4875);
DISPLAY 0.723404 (-7800 4875);
PAINT MONO (-7800 4875);
DISPLAY INVISIBLE (-7800 4875);
FORCEPROP 1 LAST BODY_TYPE PLUMBING
J 2
(-7800 4925);
DISPLAY 0.872340 (-7800 4925);
PAINT GREEN (-7800 4925);
DISPLAY INVISIBLE (-7800 4925);
FORCEPROP 1 LAST HDL_TAP TRUE
J 2
(-8125 4750);
DISPLAY 0.872340 (-8125 4750);
DISPLAY INVISIBLE (-8125 4750);
FORCEPROP 1 LAST PATH I37
J 2
(-7798 4875);
DISPLAY 0.872340 (-7798 4875);
PAINT GREEN (-7798 4875);
DISPLAY INVISIBLE (-7798 4875);
FORCEADD TAP..1
R 2
(-7800 4925);
FORCEPROP 3 LASTPIN (-7750 4925) SIG_NAME M_D_CPU1_SB_CA<1>
J 0
(-7740 4935);
DISPLAY 0.659574 (-7740 4935);
PAINT MONO (-7740 4935);
DISPLAY INVISIBLE (-7740 4935);
FORCEPROP 1 LASTPIN (-7750 4925) BN 1
J 2
(-7738 4933);
DISPLAY 0.489362 (-7738 4933);
PAINT GREEN (-7738 4933);
FORCEPROP 2 LAST CDS_LIB mstr_standard
J 0
(-7800 4925);
DISPLAY 0.723404 (-7800 4925);
PAINT MONO (-7800 4925);
DISPLAY INVISIBLE (-7800 4925);
FORCEPROP 1 LAST BODY_TYPE PLUMBING
J 2
(-7800 4975);
DISPLAY 0.872340 (-7800 4975);
PAINT GREEN (-7800 4975);
DISPLAY INVISIBLE (-7800 4975);
FORCEPROP 1 LAST HDL_TAP TRUE
J 2
(-8125 4800);
DISPLAY 0.872340 (-8125 4800);
DISPLAY INVISIBLE (-8125 4800);
FORCEPROP 1 LAST PATH I38
J 2
(-7798 4925);
DISPLAY 0.872340 (-7798 4925);
PAINT GREEN (-7798 4925);
DISPLAY INVISIBLE (-7798 4925);
FORCEADD TAP..1
R 2
(-7800 4975);
FORCEPROP 3 LASTPIN (-7750 4975) SIG_NAME M_D_CPU1_SB_CA<2>
J 0
(-7740 4985);
DISPLAY 0.659574 (-7740 4985);
PAINT MONO (-7740 4985);
DISPLAY INVISIBLE (-7740 4985);
FORCEPROP 1 LASTPIN (-7750 4975) BN 2
J 2
(-7738 4983);
DISPLAY 0.489362 (-7738 4983);
PAINT GREEN (-7738 4983);
FORCEPROP 2 LAST CDS_LIB mstr_standard
J 0
(-7800 4975);
DISPLAY 0.723404 (-7800 4975);
PAINT MONO (-7800 4975);
DISPLAY INVISIBLE (-7800 4975);
FORCEPROP 1 LAST BODY_TYPE PLUMBING
J 2
(-7800 5025);
DISPLAY 0.872340 (-7800 5025);
PAINT GREEN (-7800 5025);
DISPLAY INVISIBLE (-7800 5025);
FORCEPROP 1 LAST HDL_TAP TRUE
J 2
(-8125 4850);
DISPLAY 0.872340 (-8125 4850);
DISPLAY INVISIBLE (-8125 4850);
FORCEPROP 1 LAST PATH I39
J 2
(-7798 4975);
DISPLAY 0.872340 (-7798 4975);
PAINT GREEN (-7798 4975);
DISPLAY INVISIBLE (-7798 4975);
FORCEADD OFFPAGE..1
(-8400 3075);
FORCEPROP 2 LAST $XR0 100 
J 0
(-8652 3075);
DISPLAY 0.638298 (-8652 3075);
PAINT MONO (-8652 3075);
FORCEPROP 2 LAST PATH I4
J 0
(-8650 3125);
DISPLAY 1.021277 (-8650 3125);
DISPLAY INVISIBLE (-8650 3125);
FORCEPROP 1 LAST COMMENT_BODY TRUE
J 0
(-8275 2975);
DISPLAY 0.872340 (-8275 2975);
PAINT GREEN (-8275 2975);
DISPLAY INVISIBLE (-8275 2975);
FORCEPROP 1 LAST OFFPAGE TRUE
J 0
(-8075 2950);
DISPLAY 0.872340 (-8075 2950);
PAINT GREEN (-8075 2950);
DISPLAY INVISIBLE (-8075 2950);
FORCEPROP 2 LAST CDS_LIB mstr_standard
J 0
(-8400 3075);
DISPLAY 0.808511 (-8400 3075);
DISPLAY INVISIBLE (-8400 3075);
FORCEADD TAP..1
R 2
(-7800 5025);
FORCEPROP 3 LASTPIN (-7750 5025) SIG_NAME M_D_CPU1_SB_CA<3>
J 0
(-7740 5035);
DISPLAY 0.659574 (-7740 5035);
PAINT MONO (-7740 5035);
DISPLAY INVISIBLE (-7740 5035);
FORCEPROP 1 LASTPIN (-7750 5025) BN 3
J 2
(-7738 5033);
DISPLAY 0.489362 (-7738 5033);
PAINT GREEN (-7738 5033);
FORCEPROP 2 LAST CDS_LIB mstr_standard
J 0
(-7800 5025);
DISPLAY 0.723404 (-7800 5025);
PAINT MONO (-7800 5025);
DISPLAY INVISIBLE (-7800 5025);
FORCEPROP 1 LAST BODY_TYPE PLUMBING
J 2
(-7800 5075);
DISPLAY 0.872340 (-7800 5075);
PAINT GREEN (-7800 5075);
DISPLAY INVISIBLE (-7800 5075);
FORCEPROP 1 LAST HDL_TAP TRUE
J 2
(-8125 4900);
DISPLAY 0.872340 (-8125 4900);
DISPLAY INVISIBLE (-8125 4900);
FORCEPROP 1 LAST PATH I40
J 2
(-7798 5025);
DISPLAY 0.872340 (-7798 5025);
PAINT GREEN (-7798 5025);
DISPLAY INVISIBLE (-7798 5025);
FORCEADD TAP..1
R 2
(-7800 5075);
FORCEPROP 3 LASTPIN (-7750 5075) SIG_NAME M_D_CPU1_SB_CA<4>
J 0
(-7740 5085);
DISPLAY 0.659574 (-7740 5085);
PAINT MONO (-7740 5085);
DISPLAY INVISIBLE (-7740 5085);
FORCEPROP 1 LASTPIN (-7750 5075) BN 4
J 2
(-7738 5083);
DISPLAY 0.489362 (-7738 5083);
PAINT GREEN (-7738 5083);
FORCEPROP 2 LAST CDS_LIB mstr_standard
J 0
(-7800 5075);
DISPLAY 0.723404 (-7800 5075);
PAINT MONO (-7800 5075);
DISPLAY INVISIBLE (-7800 5075);
FORCEPROP 1 LAST BODY_TYPE PLUMBING
J 2
(-7800 5125);
DISPLAY 0.872340 (-7800 5125);
PAINT GREEN (-7800 5125);
DISPLAY INVISIBLE (-7800 5125);
FORCEPROP 1 LAST HDL_TAP TRUE
J 2
(-8125 4950);
DISPLAY 0.872340 (-8125 4950);
DISPLAY INVISIBLE (-8125 4950);
FORCEPROP 1 LAST PATH I41
J 2
(-7798 5075);
DISPLAY 0.872340 (-7798 5075);
PAINT GREEN (-7798 5075);
DISPLAY INVISIBLE (-7798 5075);
FORCEADD TAP..1
R 2
(-7800 5175);
FORCEPROP 3 LASTPIN (-7750 5175) SIG_NAME M_D_CPU1_SB_CA<6>
J 0
(-7740 5185);
DISPLAY 0.659574 (-7740 5185);
PAINT MONO (-7740 5185);
DISPLAY INVISIBLE (-7740 5185);
FORCEPROP 1 LASTPIN (-7750 5175) BN 6
J 2
(-7738 5183);
DISPLAY 0.489362 (-7738 5183);
PAINT GREEN (-7738 5183);
FORCEPROP 2 LAST CDS_LIB mstr_standard
J 0
(-7800 5175);
DISPLAY 0.723404 (-7800 5175);
PAINT MONO (-7800 5175);
DISPLAY INVISIBLE (-7800 5175);
FORCEPROP 1 LAST BODY_TYPE PLUMBING
J 2
(-7800 5225);
DISPLAY 0.872340 (-7800 5225);
PAINT GREEN (-7800 5225);
DISPLAY INVISIBLE (-7800 5225);
FORCEPROP 1 LAST HDL_TAP TRUE
J 2
(-8125 5050);
DISPLAY 0.872340 (-8125 5050);
DISPLAY INVISIBLE (-8125 5050);
FORCEPROP 1 LAST PATH I42
J 2
(-7798 5175);
DISPLAY 0.872340 (-7798 5175);
PAINT GREEN (-7798 5175);
DISPLAY INVISIBLE (-7798 5175);
FORCEADD TAP..1
R 2
(-7800 5125);
FORCEPROP 3 LASTPIN (-7750 5125) SIG_NAME M_D_CPU1_SB_CA<5>
J 0
(-7740 5135);
DISPLAY 0.659574 (-7740 5135);
PAINT MONO (-7740 5135);
DISPLAY INVISIBLE (-7740 5135);
FORCEPROP 1 LASTPIN (-7750 5125) BN 5
J 2
(-7738 5133);
DISPLAY 0.489362 (-7738 5133);
PAINT GREEN (-7738 5133);
FORCEPROP 2 LAST CDS_LIB mstr_standard
J 0
(-7800 5125);
DISPLAY 0.723404 (-7800 5125);
PAINT MONO (-7800 5125);
DISPLAY INVISIBLE (-7800 5125);
FORCEPROP 1 LAST BODY_TYPE PLUMBING
J 2
(-7800 5175);
DISPLAY 0.872340 (-7800 5175);
PAINT GREEN (-7800 5175);
DISPLAY INVISIBLE (-7800 5175);
FORCEPROP 1 LAST HDL_TAP TRUE
J 2
(-8125 5000);
DISPLAY 0.872340 (-8125 5000);
DISPLAY INVISIBLE (-8125 5000);
FORCEPROP 1 LAST PATH I43
J 2
(-7798 5125);
DISPLAY 0.872340 (-7798 5125);
PAINT GREEN (-7798 5125);
DISPLAY INVISIBLE (-7798 5125);
FORCEADD OFFPAGE..1
(-8400 5625);
FORCEPROP 2 LAST $XR0 40 
J 0
(-8621 5625);
DISPLAY 0.638298 (-8621 5625);
PAINT MONO (-8621 5625);
FORCEPROP 2 LAST PATH I44
J 0
(-8650 5675);
DISPLAY 1.021277 (-8650 5675);
DISPLAY INVISIBLE (-8650 5675);
FORCEPROP 1 LAST COMMENT_BODY TRUE
J 0
(-8275 5525);
DISPLAY 0.872340 (-8275 5525);
PAINT GREEN (-8275 5525);
DISPLAY INVISIBLE (-8275 5525);
FORCEPROP 1 LAST OFFPAGE TRUE
J 0
(-8075 5500);
DISPLAY 0.872340 (-8075 5500);
PAINT GREEN (-8075 5500);
DISPLAY INVISIBLE (-8075 5500);
FORCEPROP 2 LAST CDS_LIB mstr_standard
J 0
(-8400 5625);
DISPLAY 0.723404 (-8400 5625);
PAINT MONO (-8400 5625);
DISPLAY INVISIBLE (-8400 5625);
FORCEADD TAP..1
R 2
(-7800 5375);
FORCEPROP 3 LASTPIN (-7750 5375) SIG_NAME M_D_CPU1_SA_CA<2>
J 0
(-7740 5385);
DISPLAY 0.659574 (-7740 5385);
PAINT MONO (-7740 5385);
DISPLAY INVISIBLE (-7740 5385);
FORCEPROP 1 LASTPIN (-7750 5375) BN 2
J 2
(-7738 5383);
DISPLAY 0.489362 (-7738 5383);
PAINT GREEN (-7738 5383);
FORCEPROP 2 LAST CDS_LIB mstr_standard
J 0
(-7800 5375);
DISPLAY 0.723404 (-7800 5375);
PAINT MONO (-7800 5375);
DISPLAY INVISIBLE (-7800 5375);
FORCEPROP 1 LAST BODY_TYPE PLUMBING
J 2
(-7800 5425);
DISPLAY 0.872340 (-7800 5425);
PAINT GREEN (-7800 5425);
DISPLAY INVISIBLE (-7800 5425);
FORCEPROP 1 LAST HDL_TAP TRUE
J 2
(-8125 5250);
DISPLAY 0.872340 (-8125 5250);
DISPLAY INVISIBLE (-8125 5250);
FORCEPROP 1 LAST PATH I45
J 2
(-7798 5375);
DISPLAY 0.872340 (-7798 5375);
PAINT GREEN (-7798 5375);
DISPLAY INVISIBLE (-7798 5375);
FORCEADD TAP..1
R 2
(-7800 5425);
FORCEPROP 3 LASTPIN (-7750 5425) SIG_NAME M_D_CPU1_SA_CA<3>
J 0
(-7740 5435);
DISPLAY 0.659574 (-7740 5435);
PAINT MONO (-7740 5435);
DISPLAY INVISIBLE (-7740 5435);
FORCEPROP 1 LASTPIN (-7750 5425) BN 3
J 2
(-7738 5433);
DISPLAY 0.489362 (-7738 5433);
PAINT GREEN (-7738 5433);
FORCEPROP 2 LAST CDS_LIB mstr_standard
J 0
(-7800 5425);
DISPLAY 0.723404 (-7800 5425);
PAINT MONO (-7800 5425);
DISPLAY INVISIBLE (-7800 5425);
FORCEPROP 1 LAST BODY_TYPE PLUMBING
J 2
(-7800 5475);
DISPLAY 0.872340 (-7800 5475);
PAINT GREEN (-7800 5475);
DISPLAY INVISIBLE (-7800 5475);
FORCEPROP 1 LAST HDL_TAP TRUE
J 2
(-8125 5300);
DISPLAY 0.872340 (-8125 5300);
DISPLAY INVISIBLE (-8125 5300);
FORCEPROP 1 LAST PATH I46
J 2
(-7798 5425);
DISPLAY 0.872340 (-7798 5425);
PAINT GREEN (-7798 5425);
DISPLAY INVISIBLE (-7798 5425);
FORCEADD TAP..1
R 2
(-7800 5325);
FORCEPROP 3 LASTPIN (-7750 5325) SIG_NAME M_D_CPU1_SA_CA<1>
J 0
(-7740 5335);
DISPLAY 0.659574 (-7740 5335);
PAINT MONO (-7740 5335);
DISPLAY INVISIBLE (-7740 5335);
FORCEPROP 1 LASTPIN (-7750 5325) BN 1
J 2
(-7738 5333);
DISPLAY 0.489362 (-7738 5333);
PAINT GREEN (-7738 5333);
FORCEPROP 2 LAST CDS_LIB mstr_standard
J 0
(-7800 5325);
DISPLAY 0.723404 (-7800 5325);
PAINT MONO (-7800 5325);
DISPLAY INVISIBLE (-7800 5325);
FORCEPROP 1 LAST BODY_TYPE PLUMBING
J 2
(-7800 5375);
DISPLAY 0.872340 (-7800 5375);
PAINT GREEN (-7800 5375);
DISPLAY INVISIBLE (-7800 5375);
FORCEPROP 1 LAST HDL_TAP TRUE
J 2
(-8125 5200);
DISPLAY 0.872340 (-8125 5200);
DISPLAY INVISIBLE (-8125 5200);
FORCEPROP 1 LAST PATH I47
J 2
(-7798 5325);
DISPLAY 0.872340 (-7798 5325);
PAINT GREEN (-7798 5325);
DISPLAY INVISIBLE (-7798 5325);
FORCEADD TAP..1
R 2
(-7800 5275);
FORCEPROP 3 LASTPIN (-7750 5275) SIG_NAME M_D_CPU1_SA_CA<0>
J 0
(-7740 5285);
DISPLAY 0.659574 (-7740 5285);
PAINT MONO (-7740 5285);
DISPLAY INVISIBLE (-7740 5285);
FORCEPROP 1 LASTPIN (-7750 5275) BN 0
J 2
(-7738 5283);
DISPLAY 0.489362 (-7738 5283);
PAINT GREEN (-7738 5283);
FORCEPROP 2 LAST CDS_LIB mstr_standard
J 0
(-7800 5275);
DISPLAY 0.723404 (-7800 5275);
PAINT MONO (-7800 5275);
DISPLAY INVISIBLE (-7800 5275);
FORCEPROP 1 LAST BODY_TYPE PLUMBING
J 2
(-7800 5325);
DISPLAY 0.872340 (-7800 5325);
PAINT GREEN (-7800 5325);
DISPLAY INVISIBLE (-7800 5325);
FORCEPROP 1 LAST HDL_TAP TRUE
J 2
(-8125 5150);
DISPLAY 0.872340 (-8125 5150);
DISPLAY INVISIBLE (-8125 5150);
FORCEPROP 1 LAST PATH I48
J 2
(-7798 5275);
DISPLAY 0.872340 (-7798 5275);
PAINT GREEN (-7798 5275);
DISPLAY INVISIBLE (-7798 5275);
FORCEADD TAP..1
R 2
(-7800 5475);
FORCEPROP 3 LASTPIN (-7750 5475) SIG_NAME M_D_CPU1_SA_CA<4>
J 0
(-7740 5485);
DISPLAY 0.659574 (-7740 5485);
PAINT MONO (-7740 5485);
DISPLAY INVISIBLE (-7740 5485);
FORCEPROP 1 LASTPIN (-7750 5475) BN 4
J 2
(-7738 5483);
DISPLAY 0.489362 (-7738 5483);
PAINT GREEN (-7738 5483);
FORCEPROP 2 LAST CDS_LIB mstr_standard
J 0
(-7800 5475);
DISPLAY 0.723404 (-7800 5475);
PAINT MONO (-7800 5475);
DISPLAY INVISIBLE (-7800 5475);
FORCEPROP 1 LAST BODY_TYPE PLUMBING
J 2
(-7800 5525);
DISPLAY 0.872340 (-7800 5525);
PAINT GREEN (-7800 5525);
DISPLAY INVISIBLE (-7800 5525);
FORCEPROP 1 LAST HDL_TAP TRUE
J 2
(-8125 5350);
DISPLAY 0.872340 (-8125 5350);
DISPLAY INVISIBLE (-8125 5350);
FORCEPROP 1 LAST PATH I49
J 2
(-7798 5475);
DISPLAY 0.872340 (-7798 5475);
PAINT GREEN (-7798 5475);
DISPLAY INVISIBLE (-7798 5475);
FORCEADD TAP..1
R 2
(-7800 5575);
FORCEPROP 3 LASTPIN (-7750 5575) SIG_NAME M_D_CPU1_SA_CA<6>
J 0
(-7740 5585);
DISPLAY 0.659574 (-7740 5585);
PAINT MONO (-7740 5585);
DISPLAY INVISIBLE (-7740 5585);
FORCEPROP 1 LASTPIN (-7750 5575) BN 6
J 2
(-7738 5583);
DISPLAY 0.489362 (-7738 5583);
PAINT GREEN (-7738 5583);
FORCEPROP 2 LAST CDS_LIB mstr_standard
J 0
(-7800 5575);
DISPLAY 0.723404 (-7800 5575);
PAINT MONO (-7800 5575);
DISPLAY INVISIBLE (-7800 5575);
FORCEPROP 1 LAST BODY_TYPE PLUMBING
J 2
(-7800 5625);
DISPLAY 0.872340 (-7800 5625);
PAINT GREEN (-7800 5625);
DISPLAY INVISIBLE (-7800 5625);
FORCEPROP 1 LAST HDL_TAP TRUE
J 2
(-8125 5450);
DISPLAY 0.872340 (-8125 5450);
DISPLAY INVISIBLE (-8125 5450);
FORCEPROP 1 LAST PATH I50
J 2
(-7798 5575);
DISPLAY 0.872340 (-7798 5575);
PAINT GREEN (-7798 5575);
DISPLAY INVISIBLE (-7798 5575);
FORCEADD TAP..1
R 2
(-7800 5525);
FORCEPROP 3 LASTPIN (-7750 5525) SIG_NAME M_D_CPU1_SA_CA<5>
J 0
(-7740 5535);
DISPLAY 0.659574 (-7740 5535);
PAINT MONO (-7740 5535);
DISPLAY INVISIBLE (-7740 5535);
FORCEPROP 1 LASTPIN (-7750 5525) BN 5
J 2
(-7738 5533);
DISPLAY 0.489362 (-7738 5533);
PAINT GREEN (-7738 5533);
FORCEPROP 2 LAST CDS_LIB mstr_standard
J 0
(-7800 5525);
DISPLAY 0.723404 (-7800 5525);
PAINT MONO (-7800 5525);
DISPLAY INVISIBLE (-7800 5525);
FORCEPROP 1 LAST BODY_TYPE PLUMBING
J 2
(-7800 5575);
DISPLAY 0.872340 (-7800 5575);
PAINT GREEN (-7800 5575);
DISPLAY INVISIBLE (-7800 5575);
FORCEPROP 1 LAST HDL_TAP TRUE
J 2
(-8125 5400);
DISPLAY 0.872340 (-8125 5400);
DISPLAY INVISIBLE (-8125 5400);
FORCEPROP 1 LAST PATH I51
J 2
(-7798 5525);
DISPLAY 0.872340 (-7798 5525);
PAINT GREEN (-7798 5525);
DISPLAY INVISIBLE (-7798 5525);
FORCEADD SCONN288_DDR506112002KQ..1
(-6950 3825);
FORCEPROP 1 LAST LOCATION J30
J 0
(-7400 5900);
DISPLAY 0.468085 (-7400 5900);
PAINT SKYBLUE (-7400 5900);
FORCEPROP 0 LAST $SEC 1
J 0
(-7400 6050);
DISPLAY 0.680851 (-7400 6050);
PAINT MONO (-7400 6050);
DISPLAY INVISIBLE (-7400 6050);
FORCEPROP 2 LAST CDS_SEC 1
J 0
(-7400 6050);
DISPLAY 1.021277 (-7400 6050);
DISPLAY INVISIBLE (-7400 6050);
FORCEPROP 0 LASTPIN (-7550 3225) $PN 62
J 2
(-7560 3235);
DISPLAY 0.680851 (-7560 3235);
PAINT MONO (-7560 3235);
FORCEPROP 0 LASTPIN (-7550 5275) $PN 66
J 2
(-7560 5285);
DISPLAY 0.680851 (-7560 5285);
PAINT MONO (-7560 5285);
FORCEPROP 0 LASTPIN (-7550 4875) $PN 76
J 2
(-7560 4885);
DISPLAY 0.680851 (-7560 4885);
PAINT MONO (-7560 4885);
FORCEPROP 0 LASTPIN (-7550 5325) $PN 211
J 2
(-7560 5335);
DISPLAY 0.680851 (-7560 5335);
PAINT MONO (-7560 5335);
FORCEPROP 0 LASTPIN (-7550 4925) $PN 221
J 2
(-7560 4935);
DISPLAY 0.680851 (-7560 4935);
PAINT MONO (-7560 4935);
FORCEPROP 0 LASTPIN (-7550 5375) $PN 68
J 2
(-7560 5385);
DISPLAY 0.680851 (-7560 5385);
PAINT MONO (-7560 5385);
FORCEPROP 0 LASTPIN (-7550 4975) $PN 78
J 2
(-7560 4985);
DISPLAY 0.680851 (-7560 4985);
PAINT MONO (-7560 4985);
FORCEPROP 0 LASTPIN (-7550 5425) $PN 213
J 2
(-7560 5435);
DISPLAY 0.680851 (-7560 5435);
PAINT MONO (-7560 5435);
FORCEPROP 0 LASTPIN (-7550 5025) $PN 223
J 2
(-7560 5035);
DISPLAY 0.680851 (-7560 5035);
PAINT MONO (-7560 5035);
FORCEPROP 0 LASTPIN (-7550 5475) $PN 70
J 2
(-7560 5485);
DISPLAY 0.680851 (-7560 5485);
PAINT MONO (-7560 5485);
FORCEPROP 0 LASTPIN (-7550 5075) $PN 80
J 2
(-7560 5085);
DISPLAY 0.680851 (-7560 5085);
PAINT MONO (-7560 5085);
FORCEPROP 0 LASTPIN (-7550 5525) $PN 215
J 2
(-7560 5535);
DISPLAY 0.680851 (-7560 5535);
PAINT MONO (-7560 5535);
FORCEPROP 0 LASTPIN (-7550 5125) $PN 225
J 2
(-7560 5135);
DISPLAY 0.680851 (-7560 5135);
PAINT MONO (-7560 5135);
FORCEPROP 0 LASTPIN (-7550 5575) $PN 72
J 2
(-7560 5585);
DISPLAY 0.680851 (-7560 5585);
PAINT MONO (-7560 5585);
FORCEPROP 0 LASTPIN (-7550 5175) $PN 82
J 2
(-7560 5185);
DISPLAY 0.680851 (-7560 5185);
PAINT MONO (-7560 5185);
FORCEPROP 0 LASTPIN (-7550 3825) $PN 51
J 2
(-7560 3835);
DISPLAY 0.680851 (-7560 3835);
PAINT MONO (-7560 3835);
FORCEPROP 0 LASTPIN (-7550 3375) $PN 96
J 2
(-7560 3385);
DISPLAY 0.680851 (-7560 3385);
PAINT MONO (-7560 3385);
FORCEPROP 0 LASTPIN (-7550 3875) $PN 53
J 2
(-7560 3885);
DISPLAY 0.680851 (-7560 3885);
PAINT MONO (-7560 3885);
FORCEPROP 0 LASTPIN (-7550 3425) $PN 98
J 2
(-7560 3435);
DISPLAY 0.680851 (-7560 3435);
PAINT MONO (-7560 3435);
FORCEPROP 0 LASTPIN (-7550 3925) $PN 196
J 2
(-7560 3935);
DISPLAY 0.680851 (-7560 3935);
PAINT MONO (-7560 3935);
FORCEPROP 0 LASTPIN (-7550 3475) $PN 241
J 2
(-7560 3485);
DISPLAY 0.680851 (-7560 3485);
PAINT MONO (-7560 3485);
FORCEPROP 0 LASTPIN (-7550 3975) $PN 198
J 2
(-7560 3985);
DISPLAY 0.680851 (-7560 3985);
PAINT MONO (-7560 3985);
FORCEPROP 0 LASTPIN (-7550 3525) $PN 243
J 2
(-7560 3535);
DISPLAY 0.680851 (-7560 3535);
PAINT MONO (-7560 3535);
FORCEPROP 0 LASTPIN (-7550 4025) $PN 58
J 2
(-7560 4035);
DISPLAY 0.680851 (-7560 4035);
PAINT MONO (-7560 4035);
FORCEPROP 0 LASTPIN (-7550 3575) $PN 89
J 2
(-7560 3585);
DISPLAY 0.680851 (-7560 3585);
PAINT MONO (-7560 3585);
FORCEPROP 0 LASTPIN (-7550 4075) $PN 60
J 2
(-7560 4085);
DISPLAY 0.680851 (-7560 4085);
PAINT MONO (-7560 4085);
FORCEPROP 0 LASTPIN (-7550 3625) $PN 91
J 2
(-7560 3635);
DISPLAY 0.680851 (-7560 3635);
PAINT MONO (-7560 3635);
FORCEPROP 0 LASTPIN (-7550 4125) $PN 203
J 2
(-7560 4135);
DISPLAY 0.680851 (-7560 4135);
PAINT MONO (-7560 4135);
FORCEPROP 0 LASTPIN (-7550 3675) $PN 234
J 2
(-7560 3685);
DISPLAY 0.680851 (-7560 3685);
PAINT MONO (-7560 3685);
FORCEPROP 0 LASTPIN (-7550 4175) $PN 205
J 2
(-7560 4185);
DISPLAY 0.680851 (-7560 4185);
PAINT MONO (-7560 4185);
FORCEPROP 0 LASTPIN (-7550 3725) $PN 236
J 2
(-7560 3735);
DISPLAY 0.680851 (-7560 3735);
PAINT MONO (-7560 3735);
FORCEPROP 0 LASTPIN (-7550 4275) $PN 218
J 2
(-7560 4285);
DISPLAY 0.680851 (-7560 4285);
PAINT MONO (-7560 4285);
FORCEPROP 0 LASTPIN (-7550 4325) $PN 217
J 2
(-7560 4335);
DISPLAY 0.680851 (-7560 4335);
PAINT MONO (-7560 4335);
FORCEPROP 0 LASTPIN (-7550 4575) $PN 64
J 2
(-7560 4585);
DISPLAY 0.680851 (-7560 4585);
PAINT MONO (-7560 4585);
FORCEPROP 0 LASTPIN (-7550 4425) $PN 84
J 2
(-7560 4435);
DISPLAY 0.680851 (-7560 4435);
PAINT MONO (-7560 4435);
FORCEPROP 0 LASTPIN (-7550 4625) $PN 209
J 2
(-7560 4635);
DISPLAY 0.680851 (-7560 4635);
PAINT MONO (-7560 4635);
FORCEPROP 0 LASTPIN (-7550 4475) $PN 229
J 2
(-7560 4485);
DISPLAY 0.680851 (-7560 4485);
PAINT MONO (-7560 4485);
FORCEPROP 0 LASTPIN (-6350 4025) $PN 7
J 0
(-6340 4035);
DISPLAY 0.680851 (-6340 4035);
PAINT MONO (-6340 4035);
FORCEPROP 0 LASTPIN (-6350 2375) $PN 100
J 0
(-6340 2385);
DISPLAY 0.680851 (-6340 2385);
PAINT MONO (-6340 2385);
FORCEPROP 0 LASTPIN (-6350 4075) $PN 9
J 0
(-6340 4085);
DISPLAY 0.680851 (-6340 4085);
PAINT MONO (-6340 4085);
FORCEPROP 0 LASTPIN (-6350 2425) $PN 102
J 0
(-6340 2435);
DISPLAY 0.680851 (-6340 2435);
PAINT MONO (-6340 2435);
FORCEPROP 0 LASTPIN (-6350 4125) $PN 152
J 0
(-6340 4135);
DISPLAY 0.680851 (-6340 4135);
PAINT MONO (-6340 4135);
FORCEPROP 0 LASTPIN (-6350 2475) $PN 245
J 0
(-6340 2485);
DISPLAY 0.680851 (-6340 2485);
PAINT MONO (-6340 2485);
FORCEPROP 0 LASTPIN (-6350 4175) $PN 154
J 0
(-6340 4185);
DISPLAY 0.680851 (-6340 4185);
PAINT MONO (-6340 4185);
FORCEPROP 0 LASTPIN (-6350 2525) $PN 247
J 0
(-6340 2535);
DISPLAY 0.680851 (-6340 2535);
PAINT MONO (-6340 2535);
FORCEPROP 0 LASTPIN (-6350 4225) $PN 14
J 0
(-6340 4235);
DISPLAY 0.680851 (-6340 4235);
PAINT MONO (-6340 4235);
FORCEPROP 0 LASTPIN (-6350 2575) $PN 107
J 0
(-6340 2585);
DISPLAY 0.680851 (-6340 2585);
PAINT MONO (-6340 2585);
FORCEPROP 0 LASTPIN (-6350 4275) $PN 16
J 0
(-6340 4285);
DISPLAY 0.680851 (-6340 4285);
PAINT MONO (-6340 4285);
FORCEPROP 0 LASTPIN (-6350 2625) $PN 109
J 0
(-6340 2635);
DISPLAY 0.680851 (-6340 2635);
PAINT MONO (-6340 2635);
FORCEPROP 0 LASTPIN (-6350 4325) $PN 159
J 0
(-6340 4335);
DISPLAY 0.680851 (-6340 4335);
PAINT MONO (-6340 4335);
FORCEPROP 0 LASTPIN (-6350 2675) $PN 252
J 0
(-6340 2685);
DISPLAY 0.680851 (-6340 2685);
PAINT MONO (-6340 2685);
FORCEPROP 0 LASTPIN (-6350 4375) $PN 161
J 0
(-6340 4385);
DISPLAY 0.680851 (-6340 4385);
PAINT MONO (-6340 4385);
FORCEPROP 0 LASTPIN (-6350 2725) $PN 254
J 0
(-6340 2735);
DISPLAY 0.680851 (-6340 2735);
PAINT MONO (-6340 2735);
FORCEPROP 0 LASTPIN (-6350 4425) $PN 18
J 0
(-6340 4435);
DISPLAY 0.680851 (-6340 4435);
PAINT MONO (-6340 4435);
FORCEPROP 0 LASTPIN (-6350 2775) $PN 111
J 0
(-6340 2785);
DISPLAY 0.680851 (-6340 2785);
PAINT MONO (-6340 2785);
FORCEPROP 0 LASTPIN (-6350 4475) $PN 20
J 0
(-6340 4485);
DISPLAY 0.680851 (-6340 4485);
PAINT MONO (-6340 4485);
FORCEPROP 0 LASTPIN (-6350 2825) $PN 113
J 0
(-6340 2835);
DISPLAY 0.680851 (-6340 2835);
PAINT MONO (-6340 2835);
FORCEPROP 0 LASTPIN (-6350 4525) $PN 163
J 0
(-6340 4535);
DISPLAY 0.680851 (-6340 4535);
PAINT MONO (-6340 4535);
FORCEPROP 0 LASTPIN (-6350 2875) $PN 256
J 0
(-6340 2885);
DISPLAY 0.680851 (-6340 2885);
PAINT MONO (-6340 2885);
FORCEPROP 0 LASTPIN (-6350 4575) $PN 165
J 0
(-6340 4585);
DISPLAY 0.680851 (-6340 4585);
PAINT MONO (-6340 4585);
FORCEPROP 0 LASTPIN (-6350 2925) $PN 258
J 0
(-6340 2935);
DISPLAY 0.680851 (-6340 2935);
PAINT MONO (-6340 2935);
FORCEPROP 0 LASTPIN (-6350 4625) $PN 25
J 0
(-6340 4635);
DISPLAY 0.680851 (-6340 4635);
PAINT MONO (-6340 4635);
FORCEPROP 0 LASTPIN (-6350 2975) $PN 118
J 0
(-6340 2985);
DISPLAY 0.680851 (-6340 2985);
PAINT MONO (-6340 2985);
FORCEPROP 0 LASTPIN (-6350 4675) $PN 27
J 0
(-6340 4685);
DISPLAY 0.680851 (-6340 4685);
PAINT MONO (-6340 4685);
FORCEPROP 0 LASTPIN (-6350 3025) $PN 120
J 0
(-6340 3035);
DISPLAY 0.680851 (-6340 3035);
PAINT MONO (-6340 3035);
FORCEPROP 0 LASTPIN (-6350 4725) $PN 170
J 0
(-6340 4735);
DISPLAY 0.680851 (-6340 4735);
PAINT MONO (-6340 4735);
FORCEPROP 0 LASTPIN (-6350 3075) $PN 263
J 0
(-6340 3085);
DISPLAY 0.680851 (-6340 3085);
PAINT MONO (-6340 3085);
FORCEPROP 0 LASTPIN (-6350 4775) $PN 172
J 0
(-6340 4785);
DISPLAY 0.680851 (-6340 4785);
PAINT MONO (-6340 4785);
FORCEPROP 0 LASTPIN (-6350 3125) $PN 265
J 0
(-6340 3135);
DISPLAY 0.680851 (-6340 3135);
PAINT MONO (-6340 3135);
FORCEPROP 0 LASTPIN (-6350 4825) $PN 29
J 0
(-6340 4835);
DISPLAY 0.680851 (-6340 4835);
PAINT MONO (-6340 4835);
FORCEPROP 0 LASTPIN (-6350 3175) $PN 122
J 0
(-6340 3185);
DISPLAY 0.680851 (-6340 3185);
PAINT MONO (-6340 3185);
FORCEPROP 0 LASTPIN (-6350 4875) $PN 31
J 0
(-6340 4885);
DISPLAY 0.680851 (-6340 4885);
PAINT MONO (-6340 4885);
FORCEPROP 0 LASTPIN (-6350 3225) $PN 124
J 0
(-6340 3235);
DISPLAY 0.680851 (-6340 3235);
PAINT MONO (-6340 3235);
FORCEPROP 0 LASTPIN (-6350 4925) $PN 174
J 0
(-6340 4935);
DISPLAY 0.680851 (-6340 4935);
PAINT MONO (-6340 4935);
FORCEPROP 0 LASTPIN (-6350 3275) $PN 267
J 0
(-6340 3285);
DISPLAY 0.680851 (-6340 3285);
PAINT MONO (-6340 3285);
FORCEPROP 0 LASTPIN (-6350 4975) $PN 176
J 0
(-6340 4985);
DISPLAY 0.680851 (-6340 4985);
PAINT MONO (-6340 4985);
FORCEPROP 0 LASTPIN (-6350 3325) $PN 269
J 0
(-6340 3335);
DISPLAY 0.680851 (-6340 3335);
PAINT MONO (-6340 3335);
FORCEPROP 0 LASTPIN (-6350 5025) $PN 36
J 0
(-6340 5035);
DISPLAY 0.680851 (-6340 5035);
PAINT MONO (-6340 5035);
FORCEPROP 0 LASTPIN (-6350 3375) $PN 129
J 0
(-6340 3385);
DISPLAY 0.680851 (-6340 3385);
PAINT MONO (-6340 3385);
FORCEPROP 0 LASTPIN (-6350 5075) $PN 38
J 0
(-6340 5085);
DISPLAY 0.680851 (-6340 5085);
PAINT MONO (-6340 5085);
FORCEPROP 0 LASTPIN (-6350 3425) $PN 131
J 0
(-6340 3435);
DISPLAY 0.680851 (-6340 3435);
PAINT MONO (-6340 3435);
FORCEPROP 0 LASTPIN (-6350 5125) $PN 181
J 0
(-6340 5135);
DISPLAY 0.680851 (-6340 5135);
PAINT MONO (-6340 5135);
FORCEPROP 0 LASTPIN (-6350 3475) $PN 274
J 0
(-6340 3485);
DISPLAY 0.680851 (-6340 3485);
PAINT MONO (-6340 3485);
FORCEPROP 0 LASTPIN (-6350 5175) $PN 183
J 0
(-6340 5185);
DISPLAY 0.680851 (-6340 5185);
PAINT MONO (-6340 5185);
FORCEPROP 0 LASTPIN (-6350 3525) $PN 276
J 0
(-6340 3535);
DISPLAY 0.680851 (-6340 3535);
PAINT MONO (-6340 3535);
FORCEPROP 0 LASTPIN (-6350 5225) $PN 40
J 0
(-6340 5235);
DISPLAY 0.680851 (-6340 5235);
PAINT MONO (-6340 5235);
FORCEPROP 0 LASTPIN (-6350 3575) $PN 133
J 0
(-6340 3585);
DISPLAY 0.680851 (-6340 3585);
PAINT MONO (-6340 3585);
FORCEPROP 0 LASTPIN (-6350 5275) $PN 42
J 0
(-6340 5285);
DISPLAY 0.680851 (-6340 5285);
PAINT MONO (-6340 5285);
FORCEPROP 0 LASTPIN (-6350 3625) $PN 135
J 0
(-6340 3635);
DISPLAY 0.680851 (-6340 3635);
PAINT MONO (-6340 3635);
FORCEPROP 0 LASTPIN (-6350 5325) $PN 185
J 0
(-6340 5335);
DISPLAY 0.680851 (-6340 5335);
PAINT MONO (-6340 5335);
FORCEPROP 0 LASTPIN (-6350 3675) $PN 278
J 0
(-6340 3685);
DISPLAY 0.680851 (-6340 3685);
PAINT MONO (-6340 3685);
FORCEPROP 0 LASTPIN (-6350 5375) $PN 187
J 0
(-6340 5385);
DISPLAY 0.680851 (-6340 5385);
PAINT MONO (-6340 5385);
FORCEPROP 0 LASTPIN (-6350 3725) $PN 280
J 0
(-6340 3735);
DISPLAY 0.680851 (-6340 3735);
PAINT MONO (-6340 3735);
FORCEPROP 0 LASTPIN (-6350 5425) $PN 47
J 0
(-6340 5435);
DISPLAY 0.680851 (-6340 5435);
PAINT MONO (-6340 5435);
FORCEPROP 0 LASTPIN (-6350 3775) $PN 140
J 0
(-6340 3785);
DISPLAY 0.680851 (-6340 3785);
PAINT MONO (-6340 3785);
FORCEPROP 0 LASTPIN (-6350 5475) $PN 49
J 0
(-6340 5485);
DISPLAY 0.680851 (-6340 5485);
PAINT MONO (-6340 5485);
FORCEPROP 0 LASTPIN (-6350 3825) $PN 142
J 0
(-6340 3835);
DISPLAY 0.680851 (-6340 3835);
PAINT MONO (-6340 3835);
FORCEPROP 0 LASTPIN (-6350 5525) $PN 192
J 0
(-6340 5535);
DISPLAY 0.680851 (-6340 5535);
PAINT MONO (-6340 5535);
FORCEPROP 0 LASTPIN (-6350 3875) $PN 285
J 0
(-6340 3885);
DISPLAY 0.680851 (-6340 3885);
PAINT MONO (-6340 3885);
FORCEPROP 0 LASTPIN (-6350 5575) $PN 194
J 0
(-6340 5585);
DISPLAY 0.680851 (-6340 5585);
PAINT MONO (-6340 5585);
FORCEPROP 0 LASTPIN (-6350 3925) $PN 287
J 0
(-6340 3935);
DISPLAY 0.680851 (-6340 3935);
PAINT MONO (-6340 3935);
FORCEPROP 0 LASTPIN (-7550 3075) $PN 148
J 2
(-7560 3085);
DISPLAY 0.680851 (-7560 3085);
PAINT MONO (-7560 3085);
FORCEPROP 0 LASTPIN (-7550 2975) $PN 4
J 2
(-7560 2985);
DISPLAY 0.680851 (-7560 2985);
PAINT MONO (-7560 2985);
FORCEPROP 0 LASTPIN (-7550 3025) $PN 5
J 2
(-7560 3035);
DISPLAY 0.680851 (-7560 3035);
PAINT MONO (-7560 3035);
FORCEPROP 0 LASTPIN (-7550 2175) $PN 86
J 2
(-7560 2185);
DISPLAY 0.680851 (-7560 2185);
PAINT MONO (-7560 2185);
FORCEPROP 0 LASTPIN (-7550 2125) $PN 87
J 2
(-7560 2135);
DISPLAY 0.680851 (-7560 2135);
PAINT MONO (-7560 2135);
FORCEPROP 0 LASTPIN (-7550 4775) $PN 74
J 2
(-7560 4785);
DISPLAY 0.680851 (-7560 4785);
PAINT MONO (-7560 4785);
FORCEPROP 0 LASTPIN (-7550 4725) $PN 227
J 2
(-7560 4735);
DISPLAY 0.680851 (-7560 4735);
PAINT MONO (-7560 4735);
FORCEPROP 0 LASTPIN (-7550 2725) $PN 147
J 2
(-7560 2735);
DISPLAY 0.680851 (-7560 2735);
PAINT MONO (-7560 2735);
FORCEPROP 0 LASTPIN (-7550 3275) $PN 207
J 2
(-7560 3285);
DISPLAY 0.680851 (-7560 3285);
PAINT MONO (-7560 3285);
FORCEPROP 0 LASTPIN (-7550 2325) $PN 2
J 2
(-7560 2335);
DISPLAY 0.680851 (-7560 2335);
PAINT MONO (-7560 2335);
FORCEPROP 0 LASTPIN (-7550 2375) $PN 144
J 2
(-7560 2385);
DISPLAY 0.680851 (-7560 2385);
PAINT MONO (-7560 2385);
FORCEPROP 0 LASTPIN (-7550 2425) $PN 149
J 2
(-7560 2435);
DISPLAY 0.680851 (-7560 2435);
PAINT MONO (-7560 2435);
FORCEPROP 0 LASTPIN (-7550 2475) $PN 150
J 2
(-7560 2485);
DISPLAY 0.680851 (-7560 2485);
PAINT MONO (-7560 2485);
FORCEPROP 0 LASTPIN (-7550 2525) $PN 220
J 2
(-7560 2535);
DISPLAY 0.680851 (-7560 2535);
PAINT MONO (-7560 2535);
FORCEPROP 0 LASTPIN (-7550 2575) $PN 231
J 2
(-7560 2585);
DISPLAY 0.680851 (-7560 2585);
PAINT MONO (-7560 2585);
FORCEPROP 0 LASTPIN (-7550 2625) $PN 232
J 2
(-7560 2635);
DISPLAY 0.680851 (-7560 2635);
PAINT MONO (-7560 2635);
FORCEPROP 0 LASTPIN (-7550 3125) $PN 3
J 2
(-7560 3135);
DISPLAY 0.680851 (-7560 3135);
PAINT MONO (-7560 3135);
FORCEPROP 2 LAST PART_TYPE SMLF
J 0
(-7400 6000);
DISPLAY 1.021277 (-7400 6000);
FORCEPROP 1 LAST MATERIAL IO
J 0
(-7400 5750);
DISPLAY 0.468085 (-7400 5750);
PAINT SKYBLUE (-7400 5750);
FORCEPROP 1 LAST PART_NUMBER DFHST8FS479
J 0
(-7400 5825);
DISPLAY 0.468085 (-7400 5825);
PAINT SKYBLUE (-7400 5825);
FORCEPROP 2 LAST VALUE SCONN288_DDR506112002KQ
J 0
(-7400 5950);
DISPLAY 0.489362 (-7400 5950);
PAINT SKYBLUE (-7400 5950);
FORCEPROP 1 LAST CDS_LMAN_SYM_OUTLINE -450,1900,450,-1850
J 0
(-6950 3825);
DISPLAY 0.468085 (-6950 3825);
PAINT GREEN (-6950 3825);
DISPLAY INVISIBLE (-6950 3825);
FORCEPROP 1 LAST PATH I52
J 0
(-6950 3825);
DISPLAY 0.723404 (-6950 3825);
PAINT GREEN (-6950 3825);
DISPLAY INVISIBLE (-6950 3825);
FORCEPROP 1 LAST NEEDS_NO_SIZE TRUE
J 0
(-6950 3825);
DISPLAY 0.723404 (-6950 3825);
PAINT GREEN (-6950 3825);
DISPLAY INVISIBLE (-6950 3825);
FORCEPROP 2 LAST CDS_LIB pure_quanta
J 0
(-6950 3825);
DISPLAY INVISIBLE (-6950 3825);
FORCEADD TAP..1
(-6100 2375);
FORCEPROP 3 LASTPIN (-6150 2375) SIG_NAME M_D_CPU1_SB_DQ<0>
J 0
(-6140 2385);
DISPLAY 0.659574 (-6140 2385);
PAINT MONO (-6140 2385);
DISPLAY INVISIBLE (-6140 2385);
FORCEPROP 1 LASTPIN (-6150 2375) BN 0
J 0
(-6162 2383);
DISPLAY 0.489362 (-6162 2383);
PAINT GREEN (-6162 2383);
FORCEPROP 2 LAST CDS_LIB mstr_standard
J 0
(-6100 2375);
DISPLAY 0.723404 (-6100 2375);
PAINT MONO (-6100 2375);
DISPLAY INVISIBLE (-6100 2375);
FORCEPROP 1 LAST BODY_TYPE PLUMBING
J 0
(-6100 2425);
DISPLAY 0.872340 (-6100 2425);
PAINT GREEN (-6100 2425);
DISPLAY INVISIBLE (-6100 2425);
FORCEPROP 1 LAST HDL_TAP TRUE
J 0
(-5775 2250);
DISPLAY 0.872340 (-5775 2250);
DISPLAY INVISIBLE (-5775 2250);
FORCEPROP 1 LAST PATH I53
J 0
(-6102 2375);
DISPLAY 0.872340 (-6102 2375);
PAINT GREEN (-6102 2375);
DISPLAY INVISIBLE (-6102 2375);
FORCEADD TAP..1
(-6100 2425);
FORCEPROP 3 LASTPIN (-6150 2425) SIG_NAME M_D_CPU1_SB_DQ<1>
J 0
(-6140 2435);
DISPLAY 0.659574 (-6140 2435);
PAINT MONO (-6140 2435);
DISPLAY INVISIBLE (-6140 2435);
FORCEPROP 1 LASTPIN (-6150 2425) BN 1
J 0
(-6162 2433);
DISPLAY 0.489362 (-6162 2433);
PAINT GREEN (-6162 2433);
FORCEPROP 2 LAST CDS_LIB mstr_standard
J 0
(-6100 2425);
DISPLAY 0.723404 (-6100 2425);
PAINT MONO (-6100 2425);
DISPLAY INVISIBLE (-6100 2425);
FORCEPROP 1 LAST BODY_TYPE PLUMBING
J 0
(-6100 2475);
DISPLAY 0.872340 (-6100 2475);
PAINT GREEN (-6100 2475);
DISPLAY INVISIBLE (-6100 2475);
FORCEPROP 1 LAST HDL_TAP TRUE
J 0
(-5775 2300);
DISPLAY 0.872340 (-5775 2300);
DISPLAY INVISIBLE (-5775 2300);
FORCEPROP 1 LAST PATH I54
J 0
(-6102 2425);
DISPLAY 0.872340 (-6102 2425);
PAINT GREEN (-6102 2425);
DISPLAY INVISIBLE (-6102 2425);
FORCEADD TAP..1
(-6100 2525);
FORCEPROP 3 LASTPIN (-6150 2525) SIG_NAME M_D_CPU1_SB_DQ<3>
J 0
(-6140 2535);
DISPLAY 0.659574 (-6140 2535);
PAINT MONO (-6140 2535);
DISPLAY INVISIBLE (-6140 2535);
FORCEPROP 1 LASTPIN (-6150 2525) BN 3
J 0
(-6162 2533);
DISPLAY 0.489362 (-6162 2533);
PAINT GREEN (-6162 2533);
FORCEPROP 2 LAST CDS_LIB mstr_standard
J 0
(-6100 2525);
DISPLAY 0.723404 (-6100 2525);
PAINT MONO (-6100 2525);
DISPLAY INVISIBLE (-6100 2525);
FORCEPROP 1 LAST BODY_TYPE PLUMBING
J 0
(-6100 2575);
DISPLAY 0.872340 (-6100 2575);
PAINT GREEN (-6100 2575);
DISPLAY INVISIBLE (-6100 2575);
FORCEPROP 1 LAST HDL_TAP TRUE
J 0
(-5775 2400);
DISPLAY 0.872340 (-5775 2400);
DISPLAY INVISIBLE (-5775 2400);
FORCEPROP 1 LAST PATH I55
J 0
(-6102 2525);
DISPLAY 0.872340 (-6102 2525);
PAINT GREEN (-6102 2525);
DISPLAY INVISIBLE (-6102 2525);
FORCEADD TAP..1
(-6100 2475);
FORCEPROP 3 LASTPIN (-6150 2475) SIG_NAME M_D_CPU1_SB_DQ<2>
J 0
(-6140 2485);
DISPLAY 0.659574 (-6140 2485);
PAINT MONO (-6140 2485);
DISPLAY INVISIBLE (-6140 2485);
FORCEPROP 1 LASTPIN (-6150 2475) BN 2
J 0
(-6162 2483);
DISPLAY 0.489362 (-6162 2483);
PAINT GREEN (-6162 2483);
FORCEPROP 2 LAST CDS_LIB mstr_standard
J 0
(-6100 2475);
DISPLAY 0.723404 (-6100 2475);
PAINT MONO (-6100 2475);
DISPLAY INVISIBLE (-6100 2475);
FORCEPROP 1 LAST BODY_TYPE PLUMBING
J 0
(-6100 2525);
DISPLAY 0.872340 (-6100 2525);
PAINT GREEN (-6100 2525);
DISPLAY INVISIBLE (-6100 2525);
FORCEPROP 1 LAST HDL_TAP TRUE
J 0
(-5775 2350);
DISPLAY 0.872340 (-5775 2350);
DISPLAY INVISIBLE (-5775 2350);
FORCEPROP 1 LAST PATH I56
J 0
(-6102 2475);
DISPLAY 0.872340 (-6102 2475);
PAINT GREEN (-6102 2475);
DISPLAY INVISIBLE (-6102 2475);
FORCEADD TAP..1
(-6100 2575);
FORCEPROP 3 LASTPIN (-6150 2575) SIG_NAME M_D_CPU1_SB_DQ<4>
J 0
(-6140 2585);
DISPLAY 0.659574 (-6140 2585);
PAINT MONO (-6140 2585);
DISPLAY INVISIBLE (-6140 2585);
FORCEPROP 1 LASTPIN (-6150 2575) BN 4
J 0
(-6162 2583);
DISPLAY 0.489362 (-6162 2583);
PAINT GREEN (-6162 2583);
FORCEPROP 2 LAST CDS_LIB mstr_standard
J 0
(-6100 2575);
DISPLAY 0.723404 (-6100 2575);
PAINT MONO (-6100 2575);
DISPLAY INVISIBLE (-6100 2575);
FORCEPROP 1 LAST BODY_TYPE PLUMBING
J 0
(-6100 2625);
DISPLAY 0.872340 (-6100 2625);
PAINT GREEN (-6100 2625);
DISPLAY INVISIBLE (-6100 2625);
FORCEPROP 1 LAST HDL_TAP TRUE
J 0
(-5775 2450);
DISPLAY 0.872340 (-5775 2450);
DISPLAY INVISIBLE (-5775 2450);
FORCEPROP 1 LAST PATH I57
J 0
(-6102 2575);
DISPLAY 0.872340 (-6102 2575);
PAINT GREEN (-6102 2575);
DISPLAY INVISIBLE (-6102 2575);
FORCEADD TAP..1
(-6100 2625);
FORCEPROP 3 LASTPIN (-6150 2625) SIG_NAME M_D_CPU1_SB_DQ<5>
J 0
(-6140 2635);
DISPLAY 0.659574 (-6140 2635);
PAINT MONO (-6140 2635);
DISPLAY INVISIBLE (-6140 2635);
FORCEPROP 1 LASTPIN (-6150 2625) BN 5
J 0
(-6162 2633);
DISPLAY 0.489362 (-6162 2633);
PAINT GREEN (-6162 2633);
FORCEPROP 2 LAST CDS_LIB mstr_standard
J 0
(-6100 2625);
DISPLAY 0.723404 (-6100 2625);
PAINT MONO (-6100 2625);
DISPLAY INVISIBLE (-6100 2625);
FORCEPROP 1 LAST BODY_TYPE PLUMBING
J 0
(-6100 2675);
DISPLAY 0.872340 (-6100 2675);
PAINT GREEN (-6100 2675);
DISPLAY INVISIBLE (-6100 2675);
FORCEPROP 1 LAST HDL_TAP TRUE
J 0
(-5775 2500);
DISPLAY 0.872340 (-5775 2500);
DISPLAY INVISIBLE (-5775 2500);
FORCEPROP 1 LAST PATH I58
J 0
(-6102 2625);
DISPLAY 0.872340 (-6102 2625);
PAINT GREEN (-6102 2625);
DISPLAY INVISIBLE (-6102 2625);
FORCEADD TAP..1
(-6100 2675);
FORCEPROP 3 LASTPIN (-6150 2675) SIG_NAME M_D_CPU1_SB_DQ<6>
J 0
(-6140 2685);
DISPLAY 0.659574 (-6140 2685);
PAINT MONO (-6140 2685);
DISPLAY INVISIBLE (-6140 2685);
FORCEPROP 1 LASTPIN (-6150 2675) BN 6
J 0
(-6162 2683);
DISPLAY 0.489362 (-6162 2683);
PAINT GREEN (-6162 2683);
FORCEPROP 2 LAST CDS_LIB mstr_standard
J 0
(-6100 2675);
DISPLAY 0.723404 (-6100 2675);
PAINT MONO (-6100 2675);
DISPLAY INVISIBLE (-6100 2675);
FORCEPROP 1 LAST BODY_TYPE PLUMBING
J 0
(-6100 2725);
DISPLAY 0.872340 (-6100 2725);
PAINT GREEN (-6100 2725);
DISPLAY INVISIBLE (-6100 2725);
FORCEPROP 1 LAST HDL_TAP TRUE
J 0
(-5775 2550);
DISPLAY 0.872340 (-5775 2550);
DISPLAY INVISIBLE (-5775 2550);
FORCEPROP 1 LAST PATH I59
J 0
(-6102 2675);
DISPLAY 0.872340 (-6102 2675);
PAINT GREEN (-6102 2675);
DISPLAY INVISIBLE (-6102 2675);
FORCEADD TAP..1
(-6100 2775);
FORCEPROP 3 LASTPIN (-6150 2775) SIG_NAME M_D_CPU1_SB_DQ<8>
J 0
(-6140 2785);
DISPLAY 0.659574 (-6140 2785);
PAINT MONO (-6140 2785);
DISPLAY INVISIBLE (-6140 2785);
FORCEPROP 1 LASTPIN (-6150 2775) BN 8
J 0
(-6162 2783);
DISPLAY 0.489362 (-6162 2783);
PAINT GREEN (-6162 2783);
FORCEPROP 2 LAST CDS_LIB mstr_standard
J 0
(-6100 2775);
DISPLAY 0.723404 (-6100 2775);
PAINT MONO (-6100 2775);
DISPLAY INVISIBLE (-6100 2775);
FORCEPROP 1 LAST BODY_TYPE PLUMBING
J 0
(-6100 2825);
DISPLAY 0.872340 (-6100 2825);
PAINT GREEN (-6100 2825);
DISPLAY INVISIBLE (-6100 2825);
FORCEPROP 1 LAST HDL_TAP TRUE
J 0
(-5775 2650);
DISPLAY 0.872340 (-5775 2650);
DISPLAY INVISIBLE (-5775 2650);
FORCEPROP 1 LAST PATH I60
J 0
(-6102 2775);
DISPLAY 0.872340 (-6102 2775);
PAINT GREEN (-6102 2775);
DISPLAY INVISIBLE (-6102 2775);
FORCEADD TAP..1
(-6100 2725);
FORCEPROP 3 LASTPIN (-6150 2725) SIG_NAME M_D_CPU1_SB_DQ<7>
J 0
(-6140 2735);
DISPLAY 0.659574 (-6140 2735);
PAINT MONO (-6140 2735);
DISPLAY INVISIBLE (-6140 2735);
FORCEPROP 1 LASTPIN (-6150 2725) BN 7
J 0
(-6162 2733);
DISPLAY 0.489362 (-6162 2733);
PAINT GREEN (-6162 2733);
FORCEPROP 2 LAST CDS_LIB mstr_standard
J 0
(-6100 2725);
DISPLAY 0.723404 (-6100 2725);
PAINT MONO (-6100 2725);
DISPLAY INVISIBLE (-6100 2725);
FORCEPROP 1 LAST BODY_TYPE PLUMBING
J 0
(-6100 2775);
DISPLAY 0.872340 (-6100 2775);
PAINT GREEN (-6100 2775);
DISPLAY INVISIBLE (-6100 2775);
FORCEPROP 1 LAST HDL_TAP TRUE
J 0
(-5775 2600);
DISPLAY 0.872340 (-5775 2600);
DISPLAY INVISIBLE (-5775 2600);
FORCEPROP 1 LAST PATH I61
J 0
(-6102 2725);
DISPLAY 0.872340 (-6102 2725);
PAINT GREEN (-6102 2725);
DISPLAY INVISIBLE (-6102 2725);
FORCEADD TAP..1
(-6100 2825);
FORCEPROP 3 LASTPIN (-6150 2825) SIG_NAME M_D_CPU1_SB_DQ<9>
J 0
(-6140 2835);
DISPLAY 0.659574 (-6140 2835);
PAINT MONO (-6140 2835);
DISPLAY INVISIBLE (-6140 2835);
FORCEPROP 1 LASTPIN (-6150 2825) BN 9
J 0
(-6162 2833);
DISPLAY 0.489362 (-6162 2833);
PAINT GREEN (-6162 2833);
FORCEPROP 2 LAST CDS_LIB mstr_standard
J 0
(-6100 2825);
DISPLAY 0.723404 (-6100 2825);
PAINT MONO (-6100 2825);
DISPLAY INVISIBLE (-6100 2825);
FORCEPROP 1 LAST BODY_TYPE PLUMBING
J 0
(-6100 2875);
DISPLAY 0.872340 (-6100 2875);
PAINT GREEN (-6100 2875);
DISPLAY INVISIBLE (-6100 2875);
FORCEPROP 1 LAST HDL_TAP TRUE
J 0
(-5775 2700);
DISPLAY 0.872340 (-5775 2700);
DISPLAY INVISIBLE (-5775 2700);
FORCEPROP 1 LAST PATH I62
J 0
(-6102 2825);
DISPLAY 0.872340 (-6102 2825);
PAINT GREEN (-6102 2825);
DISPLAY INVISIBLE (-6102 2825);
FORCEADD TAP..1
(-6100 2875);
FORCEPROP 3 LASTPIN (-6150 2875) SIG_NAME M_D_CPU1_SB_DQ<10>
J 0
(-6140 2885);
DISPLAY 0.659574 (-6140 2885);
PAINT MONO (-6140 2885);
DISPLAY INVISIBLE (-6140 2885);
FORCEPROP 1 LASTPIN (-6150 2875) BN 10
J 0
(-6162 2883);
DISPLAY 0.489362 (-6162 2883);
PAINT GREEN (-6162 2883);
FORCEPROP 2 LAST CDS_LIB mstr_standard
J 0
(-6100 2875);
DISPLAY 0.723404 (-6100 2875);
PAINT MONO (-6100 2875);
DISPLAY INVISIBLE (-6100 2875);
FORCEPROP 1 LAST BODY_TYPE PLUMBING
J 0
(-6100 2925);
DISPLAY 0.872340 (-6100 2925);
PAINT GREEN (-6100 2925);
DISPLAY INVISIBLE (-6100 2925);
FORCEPROP 1 LAST HDL_TAP TRUE
J 0
(-5775 2750);
DISPLAY 0.872340 (-5775 2750);
DISPLAY INVISIBLE (-5775 2750);
FORCEPROP 1 LAST PATH I63
J 0
(-6102 2875);
DISPLAY 0.872340 (-6102 2875);
PAINT GREEN (-6102 2875);
DISPLAY INVISIBLE (-6102 2875);
FORCEADD TAP..1
(-6100 2925);
FORCEPROP 3 LASTPIN (-6150 2925) SIG_NAME M_D_CPU1_SB_DQ<11>
J 0
(-6140 2935);
DISPLAY 0.659574 (-6140 2935);
PAINT MONO (-6140 2935);
DISPLAY INVISIBLE (-6140 2935);
FORCEPROP 1 LASTPIN (-6150 2925) BN 11
J 0
(-6162 2933);
DISPLAY 0.489362 (-6162 2933);
PAINT GREEN (-6162 2933);
FORCEPROP 2 LAST CDS_LIB mstr_standard
J 0
(-6100 2925);
DISPLAY 0.723404 (-6100 2925);
PAINT MONO (-6100 2925);
DISPLAY INVISIBLE (-6100 2925);
FORCEPROP 1 LAST BODY_TYPE PLUMBING
J 0
(-6100 2975);
DISPLAY 0.872340 (-6100 2975);
PAINT GREEN (-6100 2975);
DISPLAY INVISIBLE (-6100 2975);
FORCEPROP 1 LAST HDL_TAP TRUE
J 0
(-5775 2800);
DISPLAY 0.872340 (-5775 2800);
DISPLAY INVISIBLE (-5775 2800);
FORCEPROP 1 LAST PATH I64
J 0
(-6102 2925);
DISPLAY 0.872340 (-6102 2925);
PAINT GREEN (-6102 2925);
DISPLAY INVISIBLE (-6102 2925);
FORCEADD TAP..1
(-6100 2975);
FORCEPROP 3 LASTPIN (-6150 2975) SIG_NAME M_D_CPU1_SB_DQ<12>
J 0
(-6140 2985);
DISPLAY 0.659574 (-6140 2985);
PAINT MONO (-6140 2985);
DISPLAY INVISIBLE (-6140 2985);
FORCEPROP 1 LASTPIN (-6150 2975) BN 12
J 0
(-6162 2983);
DISPLAY 0.489362 (-6162 2983);
PAINT GREEN (-6162 2983);
FORCEPROP 2 LAST CDS_LIB mstr_standard
J 0
(-6100 2975);
DISPLAY 0.723404 (-6100 2975);
PAINT MONO (-6100 2975);
DISPLAY INVISIBLE (-6100 2975);
FORCEPROP 1 LAST BODY_TYPE PLUMBING
J 0
(-6100 3025);
DISPLAY 0.872340 (-6100 3025);
PAINT GREEN (-6100 3025);
DISPLAY INVISIBLE (-6100 3025);
FORCEPROP 1 LAST HDL_TAP TRUE
J 0
(-5775 2850);
DISPLAY 0.872340 (-5775 2850);
DISPLAY INVISIBLE (-5775 2850);
FORCEPROP 1 LAST PATH I65
J 0
(-6102 2975);
DISPLAY 0.872340 (-6102 2975);
PAINT GREEN (-6102 2975);
DISPLAY INVISIBLE (-6102 2975);
FORCEADD TAP..1
(-6100 3025);
FORCEPROP 3 LASTPIN (-6150 3025) SIG_NAME M_D_CPU1_SB_DQ<13>
J 0
(-6140 3035);
DISPLAY 0.659574 (-6140 3035);
PAINT MONO (-6140 3035);
DISPLAY INVISIBLE (-6140 3035);
FORCEPROP 1 LASTPIN (-6150 3025) BN 13
J 0
(-6162 3033);
DISPLAY 0.489362 (-6162 3033);
PAINT GREEN (-6162 3033);
FORCEPROP 2 LAST CDS_LIB mstr_standard
J 0
(-6100 3025);
DISPLAY 0.723404 (-6100 3025);
PAINT MONO (-6100 3025);
DISPLAY INVISIBLE (-6100 3025);
FORCEPROP 1 LAST BODY_TYPE PLUMBING
J 0
(-6100 3075);
DISPLAY 0.872340 (-6100 3075);
PAINT GREEN (-6100 3075);
DISPLAY INVISIBLE (-6100 3075);
FORCEPROP 1 LAST HDL_TAP TRUE
J 0
(-5775 2900);
DISPLAY 0.872340 (-5775 2900);
DISPLAY INVISIBLE (-5775 2900);
FORCEPROP 1 LAST PATH I66
J 0
(-6102 3025);
DISPLAY 0.872340 (-6102 3025);
PAINT GREEN (-6102 3025);
DISPLAY INVISIBLE (-6102 3025);
FORCEADD TAP..1
(-6100 3125);
FORCEPROP 3 LASTPIN (-6150 3125) SIG_NAME M_D_CPU1_SB_DQ<15>
J 0
(-6140 3135);
DISPLAY 0.659574 (-6140 3135);
PAINT MONO (-6140 3135);
DISPLAY INVISIBLE (-6140 3135);
FORCEPROP 1 LASTPIN (-6150 3125) BN 15
J 0
(-6162 3133);
DISPLAY 0.489362 (-6162 3133);
PAINT GREEN (-6162 3133);
FORCEPROP 2 LAST CDS_LIB mstr_standard
J 0
(-6100 3125);
DISPLAY 0.723404 (-6100 3125);
PAINT MONO (-6100 3125);
DISPLAY INVISIBLE (-6100 3125);
FORCEPROP 1 LAST BODY_TYPE PLUMBING
J 0
(-6100 3175);
DISPLAY 0.872340 (-6100 3175);
PAINT GREEN (-6100 3175);
DISPLAY INVISIBLE (-6100 3175);
FORCEPROP 1 LAST HDL_TAP TRUE
J 0
(-5775 3000);
DISPLAY 0.872340 (-5775 3000);
DISPLAY INVISIBLE (-5775 3000);
FORCEPROP 1 LAST PATH I67
J 0
(-6102 3125);
DISPLAY 0.872340 (-6102 3125);
PAINT GREEN (-6102 3125);
DISPLAY INVISIBLE (-6102 3125);
FORCEADD TAP..1
(-6100 3075);
FORCEPROP 3 LASTPIN (-6150 3075) SIG_NAME M_D_CPU1_SB_DQ<14>
J 0
(-6140 3085);
DISPLAY 0.659574 (-6140 3085);
PAINT MONO (-6140 3085);
DISPLAY INVISIBLE (-6140 3085);
FORCEPROP 1 LASTPIN (-6150 3075) BN 14
J 0
(-6162 3083);
DISPLAY 0.489362 (-6162 3083);
PAINT GREEN (-6162 3083);
FORCEPROP 2 LAST CDS_LIB mstr_standard
J 0
(-6100 3075);
DISPLAY 0.723404 (-6100 3075);
PAINT MONO (-6100 3075);
DISPLAY INVISIBLE (-6100 3075);
FORCEPROP 1 LAST BODY_TYPE PLUMBING
J 0
(-6100 3125);
DISPLAY 0.872340 (-6100 3125);
PAINT GREEN (-6100 3125);
DISPLAY INVISIBLE (-6100 3125);
FORCEPROP 1 LAST HDL_TAP TRUE
J 0
(-5775 2950);
DISPLAY 0.872340 (-5775 2950);
DISPLAY INVISIBLE (-5775 2950);
FORCEPROP 1 LAST PATH I68
J 0
(-6102 3075);
DISPLAY 0.872340 (-6102 3075);
PAINT GREEN (-6102 3075);
DISPLAY INVISIBLE (-6102 3075);
FORCEADD TAP..1
(-6100 3175);
FORCEPROP 3 LASTPIN (-6150 3175) SIG_NAME M_D_CPU1_SB_DQ<16>
J 0
(-6140 3185);
DISPLAY 0.659574 (-6140 3185);
PAINT MONO (-6140 3185);
DISPLAY INVISIBLE (-6140 3185);
FORCEPROP 1 LASTPIN (-6150 3175) BN 16
J 0
(-6162 3183);
DISPLAY 0.489362 (-6162 3183);
PAINT GREEN (-6162 3183);
FORCEPROP 2 LAST CDS_LIB mstr_standard
J 0
(-6100 3175);
DISPLAY 0.723404 (-6100 3175);
PAINT MONO (-6100 3175);
DISPLAY INVISIBLE (-6100 3175);
FORCEPROP 1 LAST BODY_TYPE PLUMBING
J 0
(-6100 3225);
DISPLAY 0.872340 (-6100 3225);
PAINT GREEN (-6100 3225);
DISPLAY INVISIBLE (-6100 3225);
FORCEPROP 1 LAST HDL_TAP TRUE
J 0
(-5775 3050);
DISPLAY 0.872340 (-5775 3050);
DISPLAY INVISIBLE (-5775 3050);
FORCEPROP 1 LAST PATH I69
J 0
(-6102 3175);
DISPLAY 0.872340 (-6102 3175);
PAINT GREEN (-6102 3175);
DISPLAY INVISIBLE (-6102 3175);
FORCEADD VCC_CORE..1
(-8650 3600);
FORCEPROP 3 LASTPIN (-8650 3550) SIG_NAME P3V3_STBY\g
J 0
(-8640 3560);
DISPLAY 0.659574 (-8640 3560);
PAINT MONO (-8640 3560);
DISPLAY INVISIBLE (-8640 3560);
FORCEPROP 1 LAST HDL_POWER P3V3_STBY
J 1
(-8650 3650);
DISPLAY 0.489362 (-8650 3650);
PAINT GREEN (-8650 3650);
FORCEPROP 2 LAST CDS_LIB mstr_symbols
J 0
(-8650 3600);
PAINT MONO (-8650 3600);
DISPLAY INVISIBLE (-8650 3600);
FORCEPROP 1 LAST PATH I7
J 0
(-8600 3625);
DISPLAY 0.872340 (-8600 3625);
PAINT AQUA (-8600 3625);
DISPLAY INVISIBLE (-8600 3625);
FORCEPROP 0 LAST VOLTAGE 3.3
J 0
(-8925 3750);
DISPLAY 1.021277 (-8925 3750);
PAINT SKYBLUE (-8925 3750);
DISPLAY INVISIBLE (-8925 3750);
FORCEPROP 2 LAST ROOM PVCCINFAON_CPU1_CTRL
J 0
(-8650 3700);
DISPLAY 0.808511 (-8650 3700);
PAINT RED (-8650 3700);
DISPLAY INVISIBLE (-8650 3700);
FORCEADD TAP..1
(-6100 3225);
FORCEPROP 3 LASTPIN (-6150 3225) SIG_NAME M_D_CPU1_SB_DQ<17>
J 0
(-6140 3235);
DISPLAY 0.659574 (-6140 3235);
PAINT MONO (-6140 3235);
DISPLAY INVISIBLE (-6140 3235);
FORCEPROP 1 LASTPIN (-6150 3225) BN 17
J 0
(-6162 3233);
DISPLAY 0.489362 (-6162 3233);
PAINT GREEN (-6162 3233);
FORCEPROP 2 LAST CDS_LIB mstr_standard
J 0
(-6100 3225);
DISPLAY 0.723404 (-6100 3225);
PAINT MONO (-6100 3225);
DISPLAY INVISIBLE (-6100 3225);
FORCEPROP 1 LAST BODY_TYPE PLUMBING
J 0
(-6100 3275);
DISPLAY 0.872340 (-6100 3275);
PAINT GREEN (-6100 3275);
DISPLAY INVISIBLE (-6100 3275);
FORCEPROP 1 LAST HDL_TAP TRUE
J 0
(-5775 3100);
DISPLAY 0.872340 (-5775 3100);
DISPLAY INVISIBLE (-5775 3100);
FORCEPROP 1 LAST PATH I70
J 0
(-6102 3225);
DISPLAY 0.872340 (-6102 3225);
PAINT GREEN (-6102 3225);
DISPLAY INVISIBLE (-6102 3225);
FORCEADD TAP..1
(-6100 3275);
FORCEPROP 3 LASTPIN (-6150 3275) SIG_NAME M_D_CPU1_SB_DQ<18>
J 0
(-6140 3285);
DISPLAY 0.659574 (-6140 3285);
PAINT MONO (-6140 3285);
DISPLAY INVISIBLE (-6140 3285);
FORCEPROP 1 LASTPIN (-6150 3275) BN 18
J 0
(-6162 3283);
DISPLAY 0.489362 (-6162 3283);
PAINT GREEN (-6162 3283);
FORCEPROP 2 LAST CDS_LIB mstr_standard
J 0
(-6100 3275);
DISPLAY 0.723404 (-6100 3275);
PAINT MONO (-6100 3275);
DISPLAY INVISIBLE (-6100 3275);
FORCEPROP 1 LAST BODY_TYPE PLUMBING
J 0
(-6100 3325);
DISPLAY 0.872340 (-6100 3325);
PAINT GREEN (-6100 3325);
DISPLAY INVISIBLE (-6100 3325);
FORCEPROP 1 LAST HDL_TAP TRUE
J 0
(-5775 3150);
DISPLAY 0.872340 (-5775 3150);
DISPLAY INVISIBLE (-5775 3150);
FORCEPROP 1 LAST PATH I71
J 0
(-6102 3275);
DISPLAY 0.872340 (-6102 3275);
PAINT GREEN (-6102 3275);
DISPLAY INVISIBLE (-6102 3275);
FORCEADD TAP..1
(-6100 3325);
FORCEPROP 3 LASTPIN (-6150 3325) SIG_NAME M_D_CPU1_SB_DQ<19>
J 0
(-6140 3335);
DISPLAY 0.659574 (-6140 3335);
PAINT MONO (-6140 3335);
DISPLAY INVISIBLE (-6140 3335);
FORCEPROP 1 LASTPIN (-6150 3325) BN 19
J 0
(-6162 3333);
DISPLAY 0.489362 (-6162 3333);
PAINT GREEN (-6162 3333);
FORCEPROP 2 LAST CDS_LIB mstr_standard
J 0
(-6100 3325);
DISPLAY 0.723404 (-6100 3325);
PAINT MONO (-6100 3325);
DISPLAY INVISIBLE (-6100 3325);
FORCEPROP 1 LAST BODY_TYPE PLUMBING
J 0
(-6100 3375);
DISPLAY 0.872340 (-6100 3375);
PAINT GREEN (-6100 3375);
DISPLAY INVISIBLE (-6100 3375);
FORCEPROP 1 LAST HDL_TAP TRUE
J 0
(-5775 3200);
DISPLAY 0.872340 (-5775 3200);
DISPLAY INVISIBLE (-5775 3200);
FORCEPROP 1 LAST PATH I72
J 0
(-6102 3325);
DISPLAY 0.872340 (-6102 3325);
PAINT GREEN (-6102 3325);
DISPLAY INVISIBLE (-6102 3325);
FORCEADD TAP..1
(-6100 3425);
FORCEPROP 3 LASTPIN (-6150 3425) SIG_NAME M_D_CPU1_SB_DQ<21>
J 0
(-6140 3435);
DISPLAY 0.659574 (-6140 3435);
PAINT MONO (-6140 3435);
DISPLAY INVISIBLE (-6140 3435);
FORCEPROP 1 LASTPIN (-6150 3425) BN 21
J 0
(-6162 3433);
DISPLAY 0.489362 (-6162 3433);
PAINT GREEN (-6162 3433);
FORCEPROP 2 LAST CDS_LIB mstr_standard
J 0
(-6100 3425);
DISPLAY 0.723404 (-6100 3425);
PAINT MONO (-6100 3425);
DISPLAY INVISIBLE (-6100 3425);
FORCEPROP 1 LAST BODY_TYPE PLUMBING
J 0
(-6100 3475);
DISPLAY 0.872340 (-6100 3475);
PAINT GREEN (-6100 3475);
DISPLAY INVISIBLE (-6100 3475);
FORCEPROP 1 LAST HDL_TAP TRUE
J 0
(-5775 3300);
DISPLAY 0.872340 (-5775 3300);
DISPLAY INVISIBLE (-5775 3300);
FORCEPROP 1 LAST PATH I73
J 0
(-6102 3425);
DISPLAY 0.872340 (-6102 3425);
PAINT GREEN (-6102 3425);
DISPLAY INVISIBLE (-6102 3425);
FORCEADD TAP..1
(-6100 3375);
FORCEPROP 3 LASTPIN (-6150 3375) SIG_NAME M_D_CPU1_SB_DQ<20>
J 0
(-6140 3385);
DISPLAY 0.659574 (-6140 3385);
PAINT MONO (-6140 3385);
DISPLAY INVISIBLE (-6140 3385);
FORCEPROP 1 LASTPIN (-6150 3375) BN 20
J 0
(-6162 3383);
DISPLAY 0.489362 (-6162 3383);
PAINT GREEN (-6162 3383);
FORCEPROP 2 LAST CDS_LIB mstr_standard
J 0
(-6100 3375);
DISPLAY 0.723404 (-6100 3375);
PAINT MONO (-6100 3375);
DISPLAY INVISIBLE (-6100 3375);
FORCEPROP 1 LAST BODY_TYPE PLUMBING
J 0
(-6100 3425);
DISPLAY 0.872340 (-6100 3425);
PAINT GREEN (-6100 3425);
DISPLAY INVISIBLE (-6100 3425);
FORCEPROP 1 LAST HDL_TAP TRUE
J 0
(-5775 3250);
DISPLAY 0.872340 (-5775 3250);
DISPLAY INVISIBLE (-5775 3250);
FORCEPROP 1 LAST PATH I74
J 0
(-6102 3375);
DISPLAY 0.872340 (-6102 3375);
PAINT GREEN (-6102 3375);
DISPLAY INVISIBLE (-6102 3375);
FORCEADD TAP..1
(-6100 3475);
FORCEPROP 3 LASTPIN (-6150 3475) SIG_NAME M_D_CPU1_SB_DQ<22>
J 0
(-6140 3485);
DISPLAY 0.659574 (-6140 3485);
PAINT MONO (-6140 3485);
DISPLAY INVISIBLE (-6140 3485);
FORCEPROP 1 LASTPIN (-6150 3475) BN 22
J 0
(-6162 3483);
DISPLAY 0.489362 (-6162 3483);
PAINT GREEN (-6162 3483);
FORCEPROP 2 LAST CDS_LIB mstr_standard
J 0
(-6100 3475);
DISPLAY 0.723404 (-6100 3475);
PAINT MONO (-6100 3475);
DISPLAY INVISIBLE (-6100 3475);
FORCEPROP 1 LAST BODY_TYPE PLUMBING
J 0
(-6100 3525);
DISPLAY 0.872340 (-6100 3525);
PAINT GREEN (-6100 3525);
DISPLAY INVISIBLE (-6100 3525);
FORCEPROP 1 LAST HDL_TAP TRUE
J 0
(-5775 3350);
DISPLAY 0.872340 (-5775 3350);
DISPLAY INVISIBLE (-5775 3350);
FORCEPROP 1 LAST PATH I75
J 0
(-6102 3475);
DISPLAY 0.872340 (-6102 3475);
PAINT GREEN (-6102 3475);
DISPLAY INVISIBLE (-6102 3475);
FORCEADD TAP..1
(-6100 3525);
FORCEPROP 3 LASTPIN (-6150 3525) SIG_NAME M_D_CPU1_SB_DQ<23>
J 0
(-6140 3535);
DISPLAY 0.659574 (-6140 3535);
PAINT MONO (-6140 3535);
DISPLAY INVISIBLE (-6140 3535);
FORCEPROP 1 LASTPIN (-6150 3525) BN 23
J 0
(-6162 3533);
DISPLAY 0.489362 (-6162 3533);
PAINT GREEN (-6162 3533);
FORCEPROP 2 LAST CDS_LIB mstr_standard
J 0
(-6100 3525);
DISPLAY 0.723404 (-6100 3525);
PAINT MONO (-6100 3525);
DISPLAY INVISIBLE (-6100 3525);
FORCEPROP 1 LAST BODY_TYPE PLUMBING
J 0
(-6100 3575);
DISPLAY 0.872340 (-6100 3575);
PAINT GREEN (-6100 3575);
DISPLAY INVISIBLE (-6100 3575);
FORCEPROP 1 LAST HDL_TAP TRUE
J 0
(-5775 3400);
DISPLAY 0.872340 (-5775 3400);
DISPLAY INVISIBLE (-5775 3400);
FORCEPROP 1 LAST PATH I76
J 0
(-6102 3525);
DISPLAY 0.872340 (-6102 3525);
PAINT GREEN (-6102 3525);
DISPLAY INVISIBLE (-6102 3525);
FORCEADD TAP..1
(-6100 3575);
FORCEPROP 3 LASTPIN (-6150 3575) SIG_NAME M_D_CPU1_SB_DQ<24>
J 0
(-6140 3585);
DISPLAY 0.659574 (-6140 3585);
PAINT MONO (-6140 3585);
DISPLAY INVISIBLE (-6140 3585);
FORCEPROP 1 LASTPIN (-6150 3575) BN 24
J 0
(-6162 3583);
DISPLAY 0.489362 (-6162 3583);
PAINT GREEN (-6162 3583);
FORCEPROP 2 LAST CDS_LIB mstr_standard
J 0
(-6100 3575);
DISPLAY 0.723404 (-6100 3575);
PAINT MONO (-6100 3575);
DISPLAY INVISIBLE (-6100 3575);
FORCEPROP 1 LAST BODY_TYPE PLUMBING
J 0
(-6100 3625);
DISPLAY 0.872340 (-6100 3625);
PAINT GREEN (-6100 3625);
DISPLAY INVISIBLE (-6100 3625);
FORCEPROP 1 LAST HDL_TAP TRUE
J 0
(-5775 3450);
DISPLAY 0.872340 (-5775 3450);
DISPLAY INVISIBLE (-5775 3450);
FORCEPROP 1 LAST PATH I77
J 0
(-6102 3575);
DISPLAY 0.872340 (-6102 3575);
PAINT GREEN (-6102 3575);
DISPLAY INVISIBLE (-6102 3575);
FORCEADD TAP..1
(-6100 3675);
FORCEPROP 3 LASTPIN (-6150 3675) SIG_NAME M_D_CPU1_SB_DQ<26>
J 0
(-6140 3685);
DISPLAY 0.659574 (-6140 3685);
PAINT MONO (-6140 3685);
DISPLAY INVISIBLE (-6140 3685);
FORCEPROP 1 LASTPIN (-6150 3675) BN 26
J 0
(-6162 3683);
DISPLAY 0.489362 (-6162 3683);
PAINT GREEN (-6162 3683);
FORCEPROP 2 LAST CDS_LIB mstr_standard
J 0
(-6100 3675);
DISPLAY 0.723404 (-6100 3675);
PAINT MONO (-6100 3675);
DISPLAY INVISIBLE (-6100 3675);
FORCEPROP 1 LAST BODY_TYPE PLUMBING
J 0
(-6100 3725);
DISPLAY 0.872340 (-6100 3725);
PAINT GREEN (-6100 3725);
DISPLAY INVISIBLE (-6100 3725);
FORCEPROP 1 LAST HDL_TAP TRUE
J 0
(-5775 3550);
DISPLAY 0.872340 (-5775 3550);
DISPLAY INVISIBLE (-5775 3550);
FORCEPROP 1 LAST PATH I78
J 0
(-6102 3675);
DISPLAY 0.872340 (-6102 3675);
PAINT GREEN (-6102 3675);
DISPLAY INVISIBLE (-6102 3675);
FORCEADD TAP..1
(-6100 3625);
FORCEPROP 3 LASTPIN (-6150 3625) SIG_NAME M_D_CPU1_SB_DQ<25>
J 0
(-6140 3635);
DISPLAY 0.659574 (-6140 3635);
PAINT MONO (-6140 3635);
DISPLAY INVISIBLE (-6140 3635);
FORCEPROP 1 LASTPIN (-6150 3625) BN 25
J 0
(-6162 3633);
DISPLAY 0.489362 (-6162 3633);
PAINT GREEN (-6162 3633);
FORCEPROP 2 LAST CDS_LIB mstr_standard
J 0
(-6100 3625);
DISPLAY 0.723404 (-6100 3625);
PAINT MONO (-6100 3625);
DISPLAY INVISIBLE (-6100 3625);
FORCEPROP 1 LAST BODY_TYPE PLUMBING
J 0
(-6100 3675);
DISPLAY 0.872340 (-6100 3675);
PAINT GREEN (-6100 3675);
DISPLAY INVISIBLE (-6100 3675);
FORCEPROP 1 LAST HDL_TAP TRUE
J 0
(-5775 3500);
DISPLAY 0.872340 (-5775 3500);
DISPLAY INVISIBLE (-5775 3500);
FORCEPROP 1 LAST PATH I79
J 0
(-6102 3625);
DISPLAY 0.872340 (-6102 3625);
PAINT GREEN (-6102 3625);
DISPLAY INVISIBLE (-6102 3625);
FORCEADD OFFPAGE..5
(-8250 3225);
FORCEPROP 2 LAST $XR0 40 
J 0
(-8474 3225);
DISPLAY 0.638298 (-8474 3225);
PAINT MONO (-8474 3225);
FORCEPROP 2 LAST PATH I8
J 0
(-8550 3275);
DISPLAY 1.021277 (-8550 3275);
DISPLAY INVISIBLE (-8550 3275);
FORCEPROP 1 LAST COMMENT_BODY TRUE
J 0
(-8150 3150);
DISPLAY 0.872340 (-8150 3150);
PAINT GREEN (-8150 3150);
DISPLAY INVISIBLE (-8150 3150);
FORCEPROP 1 LAST OFFPAGE TRUE
J 0
(-7925 3100);
DISPLAY 0.872340 (-7925 3100);
PAINT GREEN (-7925 3100);
DISPLAY INVISIBLE (-7925 3100);
FORCEPROP 2 LAST CDS_LIB mstr_standard
J 0
(-8250 3225);
DISPLAY INVISIBLE (-8250 3225);
FORCEADD TAP..1
(-6100 3725);
FORCEPROP 3 LASTPIN (-6150 3725) SIG_NAME M_D_CPU1_SB_DQ<27>
J 0
(-6140 3735);
DISPLAY 0.659574 (-6140 3735);
PAINT MONO (-6140 3735);
DISPLAY INVISIBLE (-6140 3735);
FORCEPROP 1 LASTPIN (-6150 3725) BN 27
J 0
(-6162 3733);
DISPLAY 0.489362 (-6162 3733);
PAINT GREEN (-6162 3733);
FORCEPROP 2 LAST CDS_LIB mstr_standard
J 0
(-6100 3725);
DISPLAY 0.723404 (-6100 3725);
PAINT MONO (-6100 3725);
DISPLAY INVISIBLE (-6100 3725);
FORCEPROP 1 LAST BODY_TYPE PLUMBING
J 0
(-6100 3775);
DISPLAY 0.872340 (-6100 3775);
PAINT GREEN (-6100 3775);
DISPLAY INVISIBLE (-6100 3775);
FORCEPROP 1 LAST HDL_TAP TRUE
J 0
(-5775 3600);
DISPLAY 0.872340 (-5775 3600);
DISPLAY INVISIBLE (-5775 3600);
FORCEPROP 1 LAST PATH I80
J 0
(-6102 3725);
DISPLAY 0.872340 (-6102 3725);
PAINT GREEN (-6102 3725);
DISPLAY INVISIBLE (-6102 3725);
FORCEADD TAP..1
(-6100 3775);
FORCEPROP 3 LASTPIN (-6150 3775) SIG_NAME M_D_CPU1_SB_DQ<28>
J 0
(-6140 3785);
DISPLAY 0.659574 (-6140 3785);
PAINT MONO (-6140 3785);
DISPLAY INVISIBLE (-6140 3785);
FORCEPROP 1 LASTPIN (-6150 3775) BN 28
J 0
(-6162 3783);
DISPLAY 0.489362 (-6162 3783);
PAINT GREEN (-6162 3783);
FORCEPROP 2 LAST CDS_LIB mstr_standard
J 0
(-6100 3775);
DISPLAY 0.723404 (-6100 3775);
PAINT MONO (-6100 3775);
DISPLAY INVISIBLE (-6100 3775);
FORCEPROP 1 LAST BODY_TYPE PLUMBING
J 0
(-6100 3825);
DISPLAY 0.872340 (-6100 3825);
PAINT GREEN (-6100 3825);
DISPLAY INVISIBLE (-6100 3825);
FORCEPROP 1 LAST HDL_TAP TRUE
J 0
(-5775 3650);
DISPLAY 0.872340 (-5775 3650);
DISPLAY INVISIBLE (-5775 3650);
FORCEPROP 1 LAST PATH I81
J 0
(-6102 3775);
DISPLAY 0.872340 (-6102 3775);
PAINT GREEN (-6102 3775);
DISPLAY INVISIBLE (-6102 3775);
FORCEADD TAP..1
(-6100 3875);
FORCEPROP 3 LASTPIN (-6150 3875) SIG_NAME M_D_CPU1_SB_DQ<30>
J 0
(-6140 3885);
DISPLAY 0.659574 (-6140 3885);
PAINT MONO (-6140 3885);
DISPLAY INVISIBLE (-6140 3885);
FORCEPROP 1 LASTPIN (-6150 3875) BN 30
J 0
(-6162 3883);
DISPLAY 0.489362 (-6162 3883);
PAINT GREEN (-6162 3883);
FORCEPROP 2 LAST CDS_LIB mstr_standard
J 0
(-6100 3875);
DISPLAY 0.723404 (-6100 3875);
PAINT MONO (-6100 3875);
DISPLAY INVISIBLE (-6100 3875);
FORCEPROP 1 LAST BODY_TYPE PLUMBING
J 0
(-6100 3925);
DISPLAY 0.872340 (-6100 3925);
PAINT GREEN (-6100 3925);
DISPLAY INVISIBLE (-6100 3925);
FORCEPROP 1 LAST HDL_TAP TRUE
J 0
(-5775 3750);
DISPLAY 0.872340 (-5775 3750);
DISPLAY INVISIBLE (-5775 3750);
FORCEPROP 1 LAST PATH I82
J 0
(-6102 3875);
DISPLAY 0.872340 (-6102 3875);
PAINT GREEN (-6102 3875);
DISPLAY INVISIBLE (-6102 3875);
FORCEADD TAP..1
(-6100 3825);
FORCEPROP 3 LASTPIN (-6150 3825) SIG_NAME M_D_CPU1_SB_DQ<29>
J 0
(-6140 3835);
DISPLAY 0.659574 (-6140 3835);
PAINT MONO (-6140 3835);
DISPLAY INVISIBLE (-6140 3835);
FORCEPROP 1 LASTPIN (-6150 3825) BN 29
J 0
(-6162 3833);
DISPLAY 0.489362 (-6162 3833);
PAINT GREEN (-6162 3833);
FORCEPROP 2 LAST CDS_LIB mstr_standard
J 0
(-6100 3825);
DISPLAY 0.723404 (-6100 3825);
PAINT MONO (-6100 3825);
DISPLAY INVISIBLE (-6100 3825);
FORCEPROP 1 LAST BODY_TYPE PLUMBING
J 0
(-6100 3875);
DISPLAY 0.872340 (-6100 3875);
PAINT GREEN (-6100 3875);
DISPLAY INVISIBLE (-6100 3875);
FORCEPROP 1 LAST HDL_TAP TRUE
J 0
(-5775 3700);
DISPLAY 0.872340 (-5775 3700);
DISPLAY INVISIBLE (-5775 3700);
FORCEPROP 1 LAST PATH I83
J 0
(-6102 3825);
DISPLAY 0.872340 (-6102 3825);
PAINT GREEN (-6102 3825);
DISPLAY INVISIBLE (-6102 3825);
FORCEADD TAP..1
(-6100 3925);
FORCEPROP 3 LASTPIN (-6150 3925) SIG_NAME M_D_CPU1_SB_DQ<31>
J 0
(-6140 3935);
DISPLAY 0.659574 (-6140 3935);
PAINT MONO (-6140 3935);
DISPLAY INVISIBLE (-6140 3935);
FORCEPROP 1 LASTPIN (-6150 3925) BN 31
J 0
(-6162 3933);
DISPLAY 0.489362 (-6162 3933);
PAINT GREEN (-6162 3933);
FORCEPROP 2 LAST CDS_LIB mstr_standard
J 0
(-6100 3925);
DISPLAY 0.723404 (-6100 3925);
PAINT MONO (-6100 3925);
DISPLAY INVISIBLE (-6100 3925);
FORCEPROP 1 LAST BODY_TYPE PLUMBING
J 0
(-6100 3975);
DISPLAY 0.872340 (-6100 3975);
PAINT GREEN (-6100 3975);
DISPLAY INVISIBLE (-6100 3975);
FORCEPROP 1 LAST HDL_TAP TRUE
J 0
(-5775 3800);
DISPLAY 0.872340 (-5775 3800);
DISPLAY INVISIBLE (-5775 3800);
FORCEPROP 1 LAST PATH I84
J 0
(-6102 3925);
DISPLAY 0.872340 (-6102 3925);
PAINT GREEN (-6102 3925);
DISPLAY INVISIBLE (-6102 3925);
FORCEADD TAP..1
(-6100 4025);
FORCEPROP 3 LASTPIN (-6150 4025) SIG_NAME M_D_CPU1_SA_DQ<0>
J 0
(-6140 4035);
DISPLAY 0.659574 (-6140 4035);
PAINT MONO (-6140 4035);
DISPLAY INVISIBLE (-6140 4035);
FORCEPROP 1 LASTPIN (-6150 4025) BN 0
J 0
(-6162 4033);
DISPLAY 0.489362 (-6162 4033);
PAINT GREEN (-6162 4033);
FORCEPROP 2 LAST CDS_LIB mstr_standard
J 0
(-6100 4025);
DISPLAY 0.723404 (-6100 4025);
PAINT MONO (-6100 4025);
DISPLAY INVISIBLE (-6100 4025);
FORCEPROP 1 LAST BODY_TYPE PLUMBING
J 0
(-6100 4075);
DISPLAY 0.872340 (-6100 4075);
PAINT GREEN (-6100 4075);
DISPLAY INVISIBLE (-6100 4075);
FORCEPROP 1 LAST HDL_TAP TRUE
J 0
(-5775 3900);
DISPLAY 0.872340 (-5775 3900);
DISPLAY INVISIBLE (-5775 3900);
FORCEPROP 1 LAST PATH I85
J 0
(-6102 4025);
DISPLAY 0.872340 (-6102 4025);
PAINT GREEN (-6102 4025);
DISPLAY INVISIBLE (-6102 4025);
FORCEADD TAP..1
(-6100 4125);
FORCEPROP 3 LASTPIN (-6150 4125) SIG_NAME M_D_CPU1_SA_DQ<2>
J 0
(-6140 4135);
DISPLAY 0.659574 (-6140 4135);
PAINT MONO (-6140 4135);
DISPLAY INVISIBLE (-6140 4135);
FORCEPROP 1 LASTPIN (-6150 4125) BN 2
J 0
(-6162 4133);
DISPLAY 0.489362 (-6162 4133);
PAINT GREEN (-6162 4133);
FORCEPROP 2 LAST CDS_LIB mstr_standard
J 0
(-6100 4125);
DISPLAY 0.723404 (-6100 4125);
PAINT MONO (-6100 4125);
DISPLAY INVISIBLE (-6100 4125);
FORCEPROP 1 LAST BODY_TYPE PLUMBING
J 0
(-6100 4175);
DISPLAY 0.872340 (-6100 4175);
PAINT GREEN (-6100 4175);
DISPLAY INVISIBLE (-6100 4175);
FORCEPROP 1 LAST HDL_TAP TRUE
J 0
(-5775 4000);
DISPLAY 0.872340 (-5775 4000);
DISPLAY INVISIBLE (-5775 4000);
FORCEPROP 1 LAST PATH I86
J 0
(-6102 4125);
DISPLAY 0.872340 (-6102 4125);
PAINT GREEN (-6102 4125);
DISPLAY INVISIBLE (-6102 4125);
FORCEADD TAP..1
(-6100 4075);
FORCEPROP 3 LASTPIN (-6150 4075) SIG_NAME M_D_CPU1_SA_DQ<1>
J 0
(-6140 4085);
DISPLAY 0.659574 (-6140 4085);
PAINT MONO (-6140 4085);
DISPLAY INVISIBLE (-6140 4085);
FORCEPROP 1 LASTPIN (-6150 4075) BN 1
J 0
(-6162 4083);
DISPLAY 0.489362 (-6162 4083);
PAINT GREEN (-6162 4083);
FORCEPROP 2 LAST CDS_LIB mstr_standard
J 0
(-6100 4075);
DISPLAY 0.723404 (-6100 4075);
PAINT MONO (-6100 4075);
DISPLAY INVISIBLE (-6100 4075);
FORCEPROP 1 LAST BODY_TYPE PLUMBING
J 0
(-6100 4125);
DISPLAY 0.872340 (-6100 4125);
PAINT GREEN (-6100 4125);
DISPLAY INVISIBLE (-6100 4125);
FORCEPROP 1 LAST HDL_TAP TRUE
J 0
(-5775 3950);
DISPLAY 0.872340 (-5775 3950);
DISPLAY INVISIBLE (-5775 3950);
FORCEPROP 1 LAST PATH I87
J 0
(-6102 4075);
DISPLAY 0.872340 (-6102 4075);
PAINT GREEN (-6102 4075);
DISPLAY INVISIBLE (-6102 4075);
FORCEADD TAP..1
(-6100 4175);
FORCEPROP 3 LASTPIN (-6150 4175) SIG_NAME M_D_CPU1_SA_DQ<3>
J 0
(-6140 4185);
DISPLAY 0.659574 (-6140 4185);
PAINT MONO (-6140 4185);
DISPLAY INVISIBLE (-6140 4185);
FORCEPROP 1 LASTPIN (-6150 4175) BN 3
J 0
(-6162 4183);
DISPLAY 0.489362 (-6162 4183);
PAINT GREEN (-6162 4183);
FORCEPROP 2 LAST CDS_LIB mstr_standard
J 0
(-6100 4175);
DISPLAY 0.723404 (-6100 4175);
PAINT MONO (-6100 4175);
DISPLAY INVISIBLE (-6100 4175);
FORCEPROP 1 LAST BODY_TYPE PLUMBING
J 0
(-6100 4225);
DISPLAY 0.872340 (-6100 4225);
PAINT GREEN (-6100 4225);
DISPLAY INVISIBLE (-6100 4225);
FORCEPROP 1 LAST HDL_TAP TRUE
J 0
(-5775 4050);
DISPLAY 0.872340 (-5775 4050);
DISPLAY INVISIBLE (-5775 4050);
FORCEPROP 1 LAST PATH I88
J 0
(-6102 4175);
DISPLAY 0.872340 (-6102 4175);
PAINT GREEN (-6102 4175);
DISPLAY INVISIBLE (-6102 4175);
FORCEADD OFFPAGE..1
(-8250 3275);
FORCEPROP 2 LAST $XR0 40 
J 0
(-8501 3275);
DISPLAY 0.638298 (-8501 3275);
PAINT MONO (-8501 3275);
FORCEPROP 2 LAST PATH I9
J 0
(-8550 3325);
DISPLAY 1.021277 (-8550 3325);
DISPLAY INVISIBLE (-8550 3325);
FORCEPROP 1 LAST COMMENT_BODY TRUE
J 0
(-8125 3175);
DISPLAY 0.872340 (-8125 3175);
PAINT GREEN (-8125 3175);
DISPLAY INVISIBLE (-8125 3175);
FORCEPROP 1 LAST OFFPAGE TRUE
J 0
(-7925 3150);
DISPLAY 0.872340 (-7925 3150);
PAINT GREEN (-7925 3150);
DISPLAY INVISIBLE (-7925 3150);
FORCEPROP 2 LAST CDS_LIB mstr_standard
J 0
(-8250 3275);
DISPLAY 0.808511 (-8250 3275);
DISPLAY INVISIBLE (-8250 3275);
FORCEADD OFFPAGE..5
(-7300 1600);
FORCEPROP 2 LAST $XR0 100 
J 0
(-7555 1600);
DISPLAY 0.638298 (-7555 1600);
PAINT MONO (-7555 1600);
FORCEPROP 2 LAST PATH I96
J 0
(-7550 1650);
DISPLAY 1.021277 (-7550 1650);
DISPLAY INVISIBLE (-7550 1650);
FORCEPROP 1 LAST COMMENT_BODY TRUE
J 0
(-7200 1525);
DISPLAY 0.872340 (-7200 1525);
PAINT GREEN (-7200 1525);
DISPLAY INVISIBLE (-7200 1525);
FORCEPROP 1 LAST OFFPAGE TRUE
J 0
(-6975 1475);
DISPLAY 0.872340 (-6975 1475);
PAINT GREEN (-6975 1475);
DISPLAY INVISIBLE (-6975 1475);
FORCEPROP 2 LAST CDS_LIB mstr_standard
J 0
(-7300 1600);
DISPLAY 0.808511 (-7300 1600);
DISPLAY INVISIBLE (-7300 1600);
FORCEPROP 2 LAST BOM_COST MEM
J 0
(-7375 1675);
DISPLAY 0.808511 (-7375 1675);
DISPLAY INVISIBLE (-7375 1675);
FORCEADD OFFPAGE..3
(-5425 3975);
FORCEPROP 2 LAST $XR0 40 
J 0
(-5211 3975);
DISPLAY 0.638298 (-5211 3975);
PAINT MONO (-5211 3975);
FORCEPROP 2 LAST PATH I97
J 0
(-5200 4025);
DISPLAY 1.021277 (-5200 4025);
DISPLAY INVISIBLE (-5200 4025);
FORCEPROP 1 LAST COMMENT_BODY TRUE
J 0
(-5475 3875);
DISPLAY 0.872340 (-5475 3875);
PAINT GREEN (-5475 3875);
DISPLAY INVISIBLE (-5475 3875);
FORCEPROP 1 LAST OFFPAGE TRUE
J 0
(-5100 3850);
DISPLAY 0.872340 (-5100 3850);
PAINT GREEN (-5100 3850);
DISPLAY INVISIBLE (-5100 3850);
FORCEPROP 2 LAST CDS_LIB mstr_standard
J 0
(-5425 3975);
DISPLAY 0.723404 (-5425 3975);
PAINT MONO (-5425 3975);
DISPLAY INVISIBLE (-5425 3975);
FORCEADD QUANTA_TITLE_BLOCK_C..1
(-100 100);
FORCEPROP 0 LAST CDS_CON_LAST_MODIFIED Fri Mar 11 14:53:03 2022
J 0
(-1985 115);
DISPLAY INVISIBLE (-1985 115);
FORCEPROP 1 LAST CUSTOM_TXT_CDS <CON_LAST_MODIFIED>
J 0
(-1985 115);
DISPLAY 0.978723 (-1985 115);
FORCEPROP 2 LAST CUSTOM_TXT_CDS <XR_PAGE_TITLE>
J 0
(-7990 5350);
DISPLAY 0.638298 (-7990 5350);
PAINT PINK (-7990 5350);
DISPLAY INVISIBLE (-7990 5350);
FORCEPROP 1 LAST CUSTOM_TXT_CDS <NAME_2>
J 0
(-3275 150);
FORCEPROP 1 LAST CUSTOM_TXT_CDS <NAME_1>
J 0
(-3275 275);
FORCEPROP 1 LAST CUSTOM_TXT_CDS <Q_NUMBER>
J 0
(-1503 203);
DISPLAY 1.212766 (-1503 203);
FORCEPROP 1 LAST CUSTOM_TXT_CDS <Q_PROJ>
J 0
(-2482 202);
DISPLAY 1.212766 (-2482 202);
FORCEPROP 1 LAST CUSTOM_TXT_CDS <Q_REV>
J 0
(-284 203);
DISPLAY 1.212766 (-284 203);
FORCEPROP 1 LAST CUSTOM_TXT_CDS <CON_PAGE_NUM> OF <CON_TOTAL_PAGES>
J 0
(-546 118);
DISPLAY 0.978723 (-546 118);
FORCEPROP 1 LAST Q_TITLE DDR5 - CPU1 CHD
J 0
(-9425 150);
DISPLAY 2.446809 (-9425 150);
PAINT GREEN (-9425 150);
FORCEPROP 1 LAST Q_DEPT BU9
J 1
(-3863 149);
DISPLAY 1.957447 (-3863 149);
PAINT GREEN (-3863 149);
FORCEPROP 2 LAST PAGE_BORDER TRUE
J 0
(-7990 5350);
DISPLAY 0.638298 (-7990 5350);
PAINT PINK (-7990 5350);
DISPLAY INVISIBLE (-7990 5350);
FORCEPROP 1 LAST CDS_LMAN_SYM_OUTLINE -9475,6775,100,-125
J 0
(-100 100);
DISPLAY 0.468085 (-100 100);
PAINT GREEN (-100 100);
DISPLAY INVISIBLE (-100 100);
FORCEPROP 2 LAST CDS_LIB pure_quanta
J 0
(-100 100);
DISPLAY INVISIBLE (-100 100);
FORCEPROP 1 LAST COMMENT_BODY TRUE
J 0
(-88 87);
DISPLAY 0.978723 (-88 87);
PAINT GREEN (-88 87);
DISPLAY INVISIBLE (-88 87);
FORCEPROP 2 LAST CDS_XR_PAGE_TITLE CR-100 : @T6G_MB_LIB.T6G(SCH_1):PAGE100
J 0
(-7990 5350);
DISPLAY 0.638298 (-7990 5350);
PAINT PINK (-7990 5350);
DISPLAY INVISIBLE (-7990 5350);
FORCEADD DNS..2
(-8450 2475);
PAINT RED (-8450 2475);
FORCEPROP 2 LAST CDS_LIB mstr_misc
J 0
(-8450 2475);
DISPLAY INVISIBLE (-8450 2475);
FORCEPROP 1 LAST COMMENT_BODY TRUE
R 1
J 0
(-8375 2250);
DISPLAY 0.872340 (-8375 2250);
PAINT PEACH (-8375 2250);
DISPLAY INVISIBLE (-8375 2250);
WIRE 17 -1 (-7850 4200)(-7850 4225);
WIRE 17 -1 (-7850 4200)(-7850 4150);
WIRE 17 -1 (-7850 4225)(-8350 4225);
FORCEPROP 2 LAST SIG_NAME M_D_CPU1_SA_CB<7:0>
J 0
(-8300 4235);
DISPLAY 0.489362 (-8300 4235);
WIRE 17 -1 (-7850 4000)(-7850 4050);
WIRE 17 -1 (-7850 3950)(-7850 4000);
WIRE 17 -1 (-7850 4100)(-7850 4050);
WIRE 17 -1 (-7850 4100)(-7850 4150);
WIRE 17 -1 (-7850 3900)(-7850 3950);
WIRE 17 -1 (-7850 3850)(-7850 3900);
WIRE 17 -1 (-7850 3750)(-7850 3700);
WIRE 17 -1 (-7850 3750)(-7850 3775);
WIRE 17 -1 (-7850 3650)(-7850 3700);
WIRE 17 -1 (-7850 3650)(-7850 3600);
WIRE 17 -1 (-7850 3775)(-8350 3775);
FORCEPROP 2 LAST SIG_NAME M_D_CPU1_SB_CB<7:0>
J 0
(-8300 3785);
DISPLAY 0.489362 (-8300 3785);
WIRE 17 -1 (-7850 5300)(-7850 5350);
WIRE 17 -1 (-7850 5350)(-7850 5400);
WIRE 17 -1 (-7850 5400)(-7850 5450);
WIRE 17 -1 (-7850 5450)(-7850 5500);
WIRE 17 -1 (-7850 5500)(-7850 5550);
WIRE 17 -1 (-7850 5550)(-7850 5600);
WIRE 17 -1 (-7850 5600)(-7850 5625);
WIRE 17 -1 (-7850 5625)(-8350 5625);
FORCEPROP 2 LAST SIG_NAME M_D_CPU1_SA_CA<6:0>
J 0
(-8335 5635);
DISPLAY 0.489362 (-8335 5635);
WIRE 17 -1 (-7850 4900)(-7850 4950);
WIRE 17 -1 (-7850 4950)(-7850 5000);
WIRE 17 -1 (-7850 5000)(-7850 5050);
WIRE 17 -1 (-7850 5050)(-7850 5100);
WIRE 17 -1 (-7850 5100)(-7850 5150);
WIRE 17 -1 (-7850 5150)(-7850 5200);
WIRE 17 -1 (-7850 5200)(-7850 5225);
WIRE 17 -1 (-7850 5225)(-8350 5225);
FORCEPROP 2 LAST SIG_NAME M_D_CPU1_SB_CA<6:0>
J 0
(-8335 5235);
DISPLAY 0.489362 (-8335 5235);
WIRE 17 -1 (-7850 3550)(-7850 3600);
WIRE 17 -1 (-7850 3500)(-7850 3550);
WIRE 17 -1 (-7850 3450)(-7850 3500);
WIRE 17 -1 (-7850 3400)(-7850 3450);
WIRE 17 -1 (-6050 5550)(-6050 5500);
WIRE 17 -1 (-6050 5600)(-6050 5550);
WIRE 17 -1 (-6050 5500)(-6050 5450);
WIRE 17 -1 (-6050 5450)(-6050 5400);
WIRE 17 -1 (-6050 5625)(-6050 5600);
WIRE 17 -1 (-6050 5625)(-5475 5625);
FORCEPROP 2 LAST SIG_NAME M_D_CPU1_SA_DQ<31:0>
J 0
(-5985 5635);
DISPLAY 0.489362 (-5985 5635);
WIRE 17 -1 (-6050 5400)(-6050 5350);
WIRE 17 -1 (-6050 5350)(-6050 5300);
WIRE 17 -1 (-6050 5300)(-6050 5250);
WIRE 17 -1 (-6050 5250)(-6050 5200);
WIRE 17 -1 (-6050 5200)(-6050 5150);
WIRE 17 -1 (-6050 5150)(-6050 5100);
WIRE 17 -1 (-6050 5100)(-6050 5050);
WIRE 17 -1 (-6050 5050)(-6050 5000);
WIRE 17 -1 (-6050 5000)(-6050 4950);
WIRE 17 -1 (-6050 4950)(-6050 4900);
WIRE 17 -1 (-6050 4900)(-6050 4850);
WIRE 17 -1 (-6050 4800)(-6050 4850);
WIRE 17 -1 (-6050 4750)(-6050 4800);
WIRE 17 -1 (-6050 4700)(-6050 4750);
WIRE 17 -1 (-6050 4650)(-6050 4700);
WIRE 17 -1 (-6050 4650)(-6050 4600);
WIRE 17 -1 (-6050 4600)(-6050 4550);
WIRE 17 -1 (-6050 4550)(-6050 4500);
WIRE 17 -1 (-6050 4500)(-6050 4450);
WIRE 17 -1 (-6050 4450)(-6050 4400);
WIRE 17 -1 (-6050 4400)(-6050 4350);
WIRE 17 -1 (-6050 4350)(-6050 4300);
WIRE 17 -1 (-6050 4300)(-6050 4250);
WIRE 17 -1 (-6050 4200)(-6050 4250);
WIRE 17 -1 (-6050 4150)(-6050 4200);
WIRE 17 -1 (-6050 4100)(-6050 4150);
WIRE 17 -1 (-6050 4050)(-6050 4100);
WIRE 17 -1 (-6050 3950)(-6050 3900);
WIRE 17 -1 (-6050 3975)(-6050 3950);
WIRE 17 -1 (-6050 3900)(-6050 3850);
WIRE 17 -1 (-6050 3850)(-6050 3800);
WIRE 17 -1 (-6050 3975)(-5475 3975);
FORCEPROP 2 LAST SIG_NAME M_D_CPU1_SB_DQ<31:0>
J 0
(-5985 3985);
DISPLAY 0.489362 (-5985 3985);
WIRE 17 -1 (-6050 3800)(-6050 3750);
WIRE 17 -1 (-6050 3750)(-6050 3700);
WIRE 17 -1 (-6050 3700)(-6050 3650);
WIRE 17 -1 (-6050 3650)(-6050 3600);
WIRE 17 -1 (-6050 3600)(-6050 3550);
WIRE 17 -1 (-6050 3550)(-6050 3500);
WIRE 17 -1 (-6050 3500)(-6050 3450);
WIRE 17 -1 (-6050 3450)(-6050 3400);
WIRE 17 -1 (-6050 3400)(-6050 3350);
WIRE 17 -1 (-6050 3350)(-6050 3300);
WIRE 17 -1 (-6050 3300)(-6050 3250);
WIRE 17 -1 (-6050 3250)(-6050 3200);
WIRE 17 -1 (-6050 3150)(-6050 3200);
WIRE 17 -1 (-6050 3100)(-6050 3150);
WIRE 17 -1 (-6050 3050)(-6050 3100);
WIRE 17 -1 (-6050 3000)(-6050 3050);
WIRE 17 -1 (-6050 3000)(-6050 2950);
WIRE 17 -1 (-6050 2950)(-6050 2900);
WIRE 17 -1 (-6050 2900)(-6050 2850);
WIRE 17 -1 (-6050 2850)(-6050 2800);
WIRE 17 -1 (-6050 2800)(-6050 2750);
WIRE 17 -1 (-6050 2750)(-6050 2700);
WIRE 17 -1 (-6050 2700)(-6050 2650);
WIRE 17 -1 (-6050 2650)(-6050 2600);
WIRE 17 -1 (-6050 2550)(-6050 2600);
WIRE 17 -1 (-6050 2500)(-6050 2550);
WIRE 17 -1 (-6050 2450)(-6050 2500);
WIRE 17 -1 (-6050 2400)(-6050 2450);
WIRE 17 -1 (-3225 4500)(-3225 4400);
WIRE 17 -1 (-3225 4600)(-3225 4500);
WIRE 17 -1 (-3225 4400)(-3225 4300);
WIRE 17 -1 (-3225 4200)(-3225 4300);
WIRE 17 -1 (-3225 4700)(-3225 4600);
WIRE 17 -1 (-3225 4725)(-3225 4700);
WIRE 17 -1 (-3225 4100)(-3225 4200);
WIRE 17 -1 (-3225 4000)(-3225 4100);
WIRE 17 -1 (-3225 4725)(-2525 4725);
FORCEPROP 2 LAST SIG_NAME M_D_CPU1_SA_DQS_DN<9:0>
J 0
(-3160 4735);
DISPLAY 0.489362 (-3160 4735);
WIRE 17 -1 (-3425 4450)(-3425 4350);
WIRE 17 -1 (-3425 4550)(-3425 4450);
WIRE 17 -1 (-3425 4250)(-3425 4350);
WIRE 17 -1 (-3425 4150)(-3425 4250);
WIRE 17 -1 (-3425 4650)(-3425 4550);
WIRE 17 -1 (-3425 4750)(-3425 4650);
WIRE 17 -1 (-3425 4050)(-3425 4150);
WIRE 17 -1 (-3425 4050)(-3425 3950);
WIRE 17 -1 (-3425 4775)(-3425 4750);
WIRE 17 -1 (-3425 4775)(-2525 4775);
FORCEPROP 2 LAST SIG_NAME M_D_CPU1_SA_DQS_DP<9:0>
J 0
(-3160 4785);
DISPLAY 0.489362 (-3160 4785);
WIRE 17 -1 (-3425 3600)(-3425 3500);
WIRE 17 -1 (-3425 3700)(-3425 3600);
WIRE 17 -1 (-3425 3500)(-3425 3400);
WIRE 17 -1 (-3425 3400)(-3425 3300);
WIRE 17 -1 (-3425 3725)(-3425 3700);
WIRE 17 -1 (-3425 3725)(-2525 3725);
FORCEPROP 2 LAST SIG_NAME M_D_CPU1_SB_DQS_DP<9:0>
J 0
(-3160 3735);
DISPLAY 0.489362 (-3160 3735);
WIRE 17 -1 (-3225 3550)(-3225 3450);
WIRE 17 -1 (-3225 3650)(-3225 3550);
WIRE 17 -1 (-3225 3450)(-3225 3350);
WIRE 17 -1 (-3225 3350)(-3225 3250);
WIRE 17 -1 (-3225 3675)(-3225 3650);
WIRE 17 -1 (-3225 3675)(-2525 3675);
FORCEPROP 2 LAST SIG_NAME M_D_CPU1_SB_DQS_DN<9:0>
J 0
(-3160 3685);
DISPLAY 0.489362 (-3160 3685);
WIRE 17 -1 (-3425 3200)(-3425 3300);
WIRE 17 -1 (-3425 3100)(-3425 3200);
WIRE 17 -1 (-3425 3000)(-3425 3100);
WIRE 17 -1 (-3225 3900)(-3225 3800);
WIRE 17 -1 (-3225 4000)(-3225 3900);
WIRE 17 -1 (-3425 3950)(-3425 3850);
WIRE 17 -1 (-3225 2850)(-3225 2750);
WIRE 17 -1 (-3225 2950)(-3225 2850);
WIRE 17 -1 (-3225 2950)(-3225 3050);
WIRE 17 -1 (-3225 3050)(-3225 3150);
WIRE 17 -1 (-3225 3150)(-3225 3250);
WIRE 17 -1 (-3425 2900)(-3425 2800);
WIRE 17 -1 (-3425 3000)(-3425 2900);
WIRE 16 -1 (-6525 1250)(-6525 1325);
WIRE 16 -1 (-8750 3225)(-8750 3300);
WIRE 16 -1 (-8475 2575)(-8475 2600);
WIRE 16 -1 (-7650 2975)(-7650 2875);
WIRE 16 -1 (-7550 2975)(-7650 2975);
FORCEPROP 2 LAST SIG_NAME I3C_SPD_DDRD_CPU1_SCL
J 0
(-8035 2985);
DISPLAY 0.446809 (-8035 2985);
FORCEPROP 2 LASTPROP $XRERR UNIQUE?
J 0
(-8275 2985);
DISPLAY 0.638298 (-8275 2985);
PAINT MONO (-8275 2985);
DISPLAY INVISIBLE (-8275 2985);
WIRE 16 -1 (-7650 2875)(-7750 2875);
WIRE 16 -1 (-7950 2875)(-8375 2875);
FORCEPROP 2 LAST SIG_NAME I3C_SPD_DDRAF_CPU1_SCL
J 0
(-8435 2885);
DISPLAY 0.489362 (-8435 2885);
WIRE 16 -1 (-7550 2725)(-8275 2725);
FORCEPROP 2 LAST SIG_NAME PWRGD_CHD_CPU1_DIMM
J 0
(-8160 2735);
DISPLAY 0.489362 (-8160 2735);
FORCEPROP 2 LASTPROP $XRERR UNIQUE?
J 0
(-8400 2735);
DISPLAY 0.638298 (-8400 2735);
PAINT MONO (-8400 2735);
DISPLAY INVISIBLE (-8400 2735);
WIRE 16 -1 (-8275 2325)(-8275 2725);
WIRE 16 -1 (-8275 2325)(-8475 2325);
WIRE 16 -1 (-8475 2325)(-8500 2325);
WIRE 16 -1 (-8475 2375)(-8475 2325);
WIRE 16 -1 (-7550 3025)(-8350 3025);
FORCEPROP 2 LAST SIG_NAME I3C_SPD_DDRAF_CPU1_SDA
J 0
(-8360 3035);
DISPLAY 0.489362 (-8360 3035);
WIRE 16 -1 (-7550 3075)(-8350 3075);
FORCEPROP 2 LAST SIG_NAME PD_CHD_CPU1_DIMM_SAA
J 0
(-8325 3085);
DISPLAY 0.489362 (-8325 3085);
WIRE 16 -1 (-8650 3125)(-7550 3125);
WIRE 16 -1 (-8650 3525)(-8650 3125);
WIRE 16 -1 (-8650 3550)(-8650 3525);
WIRE 16 -1 (-8750 3525)(-8650 3525);
WIRE 16 -1 (-8750 3500)(-8750 3525);
WIRE 16 -1 (-7550 2325)(-8150 2325);
FORCEPROP 2 LAST SIG_NAME TP_CHD_CPU1_DIMM_RFU_0
J 0
(-8160 2335);
DISPLAY 0.489362 (-8160 2335);
FORCEPROP 2 LASTPROP $XRERR UNIQUE?
J 0
(-8390 2325);
DISPLAY 0.638298 (-8390 2325);
PAINT MONO (-8390 2325);
DISPLAY INVISIBLE (-8390 2325);
WIRE 16 -1 (-7550 2375)(-8150 2375);
FORCEPROP 2 LAST SIG_NAME TP_CHD_CPU1_DIMM_RFU_1
J 0
(-8160 2385);
DISPLAY 0.489362 (-8160 2385);
FORCEPROP 2 LASTPROP $XRERR UNIQUE?
J 0
(-8390 2375);
DISPLAY 0.638298 (-8390 2375);
PAINT MONO (-8390 2375);
DISPLAY INVISIBLE (-8390 2375);
WIRE 16 -1 (-7550 2475)(-8150 2475);
FORCEPROP 2 LAST SIG_NAME TP_CHD_CPU1_DIMM_RFU_3
J 0
(-8160 2485);
DISPLAY 0.489362 (-8160 2485);
FORCEPROP 2 LASTPROP $XRERR UNIQUE?
J 0
(-8390 2475);
DISPLAY 0.638298 (-8390 2475);
PAINT MONO (-8390 2475);
DISPLAY INVISIBLE (-8390 2475);
WIRE 16 -1 (-7550 2625)(-8150 2625);
FORCEPROP 2 LAST SIG_NAME TP_CHD_CPU1_DIMM_RFU_6
J 0
(-8160 2635);
DISPLAY 0.489362 (-8160 2635);
FORCEPROP 2 LASTPROP $XRERR UNIQUE?
J 0
(-8390 2625);
DISPLAY 0.638298 (-8390 2625);
PAINT MONO (-8390 2625);
DISPLAY INVISIBLE (-8390 2625);
WIRE 16 -1 (-9050 2325)(-8700 2325);
FORCEPROP 2 LAST SIG_NAME PWRGD_CHAF_CPU1
J 0
(-9060 2335);
DISPLAY 0.489362 (-9060 2335);
WIRE 16 -1 (-2200 5300)(-1900 5300);
WIRE 16 -1 (-2200 5350)(-2200 5300);
WIRE 16 -1 (-1900 5350)(-2200 5350);
WIRE 16 -1 (-2200 5350)(-2200 5400);
WIRE 16 -1 (-1900 5400)(-2200 5400);
WIRE 16 -1 (-2200 5400)(-2200 6000);
WIRE 16 -1 (-2325 6000)(-2200 6000);
WIRE 16 -1 (-2325 6000)(-2900 6000);
WIRE 16 -1 (-2325 6000)(-2325 5900);
WIRE 16 -1 (-2900 6000)(-2900 6075);
WIRE 16 -1 (-2900 5900)(-2900 6000);
WIRE 16 -1 (-2325 5575)(-2900 5575);
WIRE 16 -1 (-2325 5575)(-2325 5700);
WIRE 16 -1 (-2900 5575)(-2900 5700);
WIRE 16 -1 (-2900 5575)(-2900 5500);
WIRE 16 -1 (-400 5400)(-400 5350);
WIRE 16 -1 (-400 5400)(-700 5400);
WIRE 16 -1 (-400 5350)(-400 5300);
WIRE 16 -1 (-400 5350)(-700 5350);
WIRE 16 -1 (-400 5300)(-400 5250);
WIRE 16 -1 (-400 5300)(-700 5300);
WIRE 16 -1 (-400 5250)(-400 5200);
WIRE 16 -1 (-400 5250)(-700 5250);
WIRE 16 -1 (-400 5200)(-400 5150);
WIRE 16 -1 (-400 5200)(-700 5200);
WIRE 16 -1 (-400 5150)(-700 5150);
WIRE 16 -1 (-400 5150)(-400 5100);
WIRE 16 -1 (-400 5100)(-400 5050);
WIRE 16 -1 (-400 5100)(-700 5100);
WIRE 16 -1 (-400 5050)(-400 5000);
WIRE 16 -1 (-400 5050)(-700 5050);
WIRE 16 -1 (-400 5000)(-400 4950);
WIRE 16 -1 (-400 5000)(-700 5000);
WIRE 16 -1 (-400 4950)(-400 4900);
WIRE 16 -1 (-400 4950)(-700 4950);
WIRE 16 -1 (-400 4900)(-400 4850);
WIRE 16 -1 (-400 4900)(-700 4900);
WIRE 16 -1 (-400 4850)(-400 4800);
WIRE 16 -1 (-400 4850)(-700 4850);
WIRE 16 -1 (-400 4800)(-400 4750);
WIRE 16 -1 (-400 4800)(-700 4800);
WIRE 16 -1 (-400 4750)(-400 4700);
WIRE 16 -1 (-400 4750)(-700 4750);
WIRE 16 -1 (-400 4700)(-400 4650);
WIRE 16 -1 (-400 4700)(-700 4700);
WIRE 16 -1 (-400 4650)(-400 4600);
WIRE 16 -1 (-400 4650)(-700 4650);
WIRE 16 -1 (-400 4600)(-400 4550);
WIRE 16 -1 (-400 4600)(-700 4600);
WIRE 16 -1 (-400 4550)(-400 4500);
WIRE 16 -1 (-400 4550)(-700 4550);
WIRE 16 -1 (-400 4500)(-400 4450);
WIRE 16 -1 (-400 4500)(-700 4500);
WIRE 16 -1 (-400 4450)(-400 4400);
WIRE 16 -1 (-400 4450)(-700 4450);
WIRE 16 -1 (-400 4400)(-400 4350);
WIRE 16 -1 (-400 4400)(-700 4400);
WIRE 16 -1 (-400 4350)(-400 4300);
WIRE 16 -1 (-400 4350)(-700 4350);
WIRE 16 -1 (-400 4300)(-400 4250);
WIRE 16 -1 (-400 4300)(-700 4300);
WIRE 16 -1 (-400 4250)(-400 4200);
WIRE 16 -1 (-400 4250)(-700 4250);
WIRE 16 -1 (-400 4200)(-400 4150);
WIRE 16 -1 (-400 4200)(-700 4200);
WIRE 16 -1 (-400 4150)(-400 4100);
WIRE 16 -1 (-400 4150)(-700 4150);
WIRE 16 -1 (-400 4100)(-700 4100);
WIRE 16 -1 (-400 4100)(-400 4050);
WIRE 16 -1 (-400 4050)(-400 4000);
WIRE 16 -1 (-400 4050)(-700 4050);
WIRE 16 -1 (-400 4000)(-400 3950);
WIRE 16 -1 (-400 4000)(-700 4000);
WIRE 16 -1 (-400 3950)(-400 3900);
WIRE 16 -1 (-400 3950)(-700 3950);
WIRE 16 -1 (-400 3900)(-400 3850);
WIRE 16 -1 (-400 3900)(-700 3900);
WIRE 16 -1 (-400 3850)(-400 3800);
WIRE 16 -1 (-400 3850)(-700 3850);
WIRE 16 -1 (-400 3800)(-400 3750);
WIRE 16 -1 (-400 3800)(-700 3800);
WIRE 16 -1 (-400 3750)(-400 3700);
WIRE 16 -1 (-400 3750)(-700 3750);
WIRE 16 -1 (-400 3700)(-400 3650);
WIRE 16 -1 (-400 3700)(-700 3700);
WIRE 16 -1 (-400 3650)(-400 3600);
WIRE 16 -1 (-400 3650)(-700 3650);
WIRE 16 -1 (-400 3600)(-400 3550);
WIRE 16 -1 (-400 3600)(-700 3600);
WIRE 16 -1 (-400 3550)(-400 3500);
WIRE 16 -1 (-400 3550)(-700 3550);
WIRE 16 -1 (-400 3500)(-400 3450);
WIRE 16 -1 (-400 3500)(-700 3500);
WIRE 16 -1 (-400 3450)(-400 3400);
WIRE 16 -1 (-400 3450)(-700 3450);
WIRE 16 -1 (-400 3400)(-400 3350);
WIRE 16 -1 (-400 3400)(-700 3400);
WIRE 16 -1 (-400 3350)(-400 3300);
WIRE 16 -1 (-400 3350)(-700 3350);
WIRE 16 -1 (-400 3300)(-400 3250);
WIRE 16 -1 (-400 3300)(-700 3300);
WIRE 16 -1 (-400 3250)(-400 3200);
WIRE 16 -1 (-400 3250)(-700 3250);
WIRE 16 -1 (-400 3200)(-400 3150);
WIRE 16 -1 (-400 3200)(-700 3200);
WIRE 16 -1 (-400 3150)(-400 3100);
WIRE 16 -1 (-400 3150)(-700 3150);
WIRE 16 -1 (-400 3100)(-700 3100);
WIRE 16 -1 (-400 3100)(-400 3050);
WIRE 16 -1 (-400 3050)(-400 3000);
WIRE 16 -1 (-400 3050)(-700 3050);
WIRE 16 -1 (-400 3000)(-400 2950);
WIRE 16 -1 (-400 3000)(-700 3000);
WIRE 16 -1 (-400 2950)(-400 2900);
WIRE 16 -1 (-400 2950)(-700 2950);
WIRE 16 -1 (-400 2900)(-400 2850);
WIRE 16 -1 (-400 2900)(-700 2900);
WIRE 16 -1 (-400 2850)(-400 2800);
WIRE 16 -1 (-400 2850)(-700 2850);
WIRE 16 -1 (-400 2800)(-400 2750);
WIRE 16 -1 (-400 2800)(-700 2800);
WIRE 16 -1 (-400 2750)(-400 2700);
WIRE 16 -1 (-400 2750)(-700 2750);
WIRE 16 -1 (-400 2700)(-400 2650);
WIRE 16 -1 (-400 2700)(-700 2700);
WIRE 16 -1 (-400 2650)(-400 2600);
WIRE 16 -1 (-400 2650)(-700 2650);
WIRE 16 -1 (-400 2600)(-400 2550);
WIRE 16 -1 (-400 2600)(-700 2600);
WIRE 16 -1 (-400 2550)(-400 2500);
WIRE 16 -1 (-400 2550)(-700 2550);
WIRE 16 -1 (-400 2500)(-400 2450);
WIRE 16 -1 (-400 2500)(-700 2500);
WIRE 16 -1 (-400 2450)(-400 2400);
WIRE 16 -1 (-400 2450)(-700 2450);
WIRE 16 -1 (-400 2400)(-400 2350);
WIRE 16 -1 (-400 2400)(-700 2400);
WIRE 16 -1 (-400 2350)(-400 2300);
WIRE 16 -1 (-400 2350)(-700 2350);
WIRE 16 -1 (-400 2300)(-400 2250);
WIRE 16 -1 (-400 2300)(-700 2300);
WIRE 16 -1 (-400 2250)(-400 2150);
WIRE 16 -1 (-400 2250)(-700 2250);
WIRE 16 -1 (-400 2150)(-400 2100);
WIRE 16 -1 (-400 2150)(-700 2150);
WIRE 16 -1 (-400 2100)(-400 2050);
WIRE 16 -1 (-400 2100)(-700 2100);
WIRE 16 -1 (-400 2050)(-700 2050);
WIRE 16 -1 (-400 2050)(-400 1850);
WIRE 16 -1 (-1900 2150)(-2200 2150);
WIRE 16 -1 (-2200 2200)(-2200 2150);
WIRE 16 -1 (-2200 2150)(-2200 2050);
WIRE 16 -1 (-1900 2200)(-2200 2200);
WIRE 16 -1 (-2200 2250)(-2200 2200);
WIRE 16 -1 (-1900 2250)(-2200 2250);
WIRE 16 -1 (-2200 2300)(-2200 2250);
WIRE 16 -1 (-1900 2300)(-2200 2300);
WIRE 16 -1 (-2200 2350)(-2200 2300);
WIRE 16 -1 (-1900 2350)(-2200 2350);
WIRE 16 -1 (-2200 2400)(-2200 2350);
WIRE 16 -1 (-1900 2400)(-2200 2400);
WIRE 16 -1 (-2200 2450)(-2200 2400);
WIRE 16 -1 (-1900 2450)(-2200 2450);
WIRE 16 -1 (-2200 2500)(-2200 2450);
WIRE 16 -1 (-1900 2500)(-2200 2500);
WIRE 16 -1 (-2200 2550)(-2200 2500);
WIRE 16 -1 (-1900 2550)(-2200 2550);
WIRE 16 -1 (-2200 2600)(-2200 2550);
WIRE 16 -1 (-1900 2600)(-2200 2600);
WIRE 16 -1 (-2200 2650)(-2200 2600);
WIRE 16 -1 (-1900 2650)(-2200 2650);
WIRE 16 -1 (-2200 2700)(-2200 2650);
WIRE 16 -1 (-1900 2700)(-2200 2700);
WIRE 16 -1 (-2200 2750)(-2200 2700);
WIRE 16 -1 (-1900 2750)(-2200 2750);
WIRE 16 -1 (-2200 2800)(-2200 2750);
WIRE 16 -1 (-1900 2800)(-2200 2800);
WIRE 16 -1 (-2200 2850)(-2200 2800);
WIRE 16 -1 (-1900 2850)(-2200 2850);
WIRE 16 -1 (-2200 2900)(-2200 2850);
WIRE 16 -1 (-1900 2900)(-2200 2900);
WIRE 16 -1 (-2200 2950)(-2200 2900);
WIRE 16 -1 (-1900 2950)(-2200 2950);
WIRE 16 -1 (-2200 3000)(-2200 2950);
WIRE 16 -1 (-1900 3000)(-2200 3000);
WIRE 16 -1 (-2200 3050)(-2200 3000);
WIRE 16 -1 (-1900 3050)(-2200 3050);
WIRE 16 -1 (-2200 3100)(-2200 3050);
WIRE 16 -1 (-1900 3100)(-2200 3100);
WIRE 16 -1 (-2200 3150)(-2200 3100);
WIRE 16 -1 (-1900 3150)(-2200 3150);
WIRE 16 -1 (-2200 3200)(-2200 3150);
WIRE 16 -1 (-1900 3200)(-2200 3200);
WIRE 16 -1 (-2200 3250)(-2200 3200);
WIRE 16 -1 (-1900 3250)(-2200 3250);
WIRE 16 -1 (-2200 3300)(-2200 3250);
WIRE 16 -1 (-1900 3300)(-2200 3300);
WIRE 16 -1 (-2200 3350)(-2200 3300);
WIRE 16 -1 (-1900 3350)(-2200 3350);
WIRE 16 -1 (-2200 3400)(-2200 3350);
WIRE 16 -1 (-1900 3400)(-2200 3400);
WIRE 16 -1 (-2200 3450)(-2200 3400);
WIRE 16 -1 (-1900 3450)(-2200 3450);
WIRE 16 -1 (-2200 3500)(-2200 3450);
WIRE 16 -1 (-1900 3500)(-2200 3500);
WIRE 16 -1 (-2200 3550)(-2200 3500);
WIRE 16 -1 (-1900 3550)(-2200 3550);
WIRE 16 -1 (-2200 3600)(-2200 3550);
WIRE 16 -1 (-1900 3600)(-2200 3600);
WIRE 16 -1 (-2200 3650)(-2200 3600);
WIRE 16 -1 (-1900 3650)(-2200 3650);
WIRE 16 -1 (-2200 3700)(-2200 3650);
WIRE 16 -1 (-1900 3700)(-2200 3700);
WIRE 16 -1 (-2200 3750)(-2200 3700);
WIRE 16 -1 (-1900 3750)(-2200 3750);
WIRE 16 -1 (-2200 3800)(-2200 3750);
WIRE 16 -1 (-1900 3800)(-2200 3800);
WIRE 16 -1 (-2200 3850)(-2200 3800);
WIRE 16 -1 (-1900 3850)(-2200 3850);
WIRE 16 -1 (-2200 3900)(-2200 3850);
WIRE 16 -1 (-1900 3900)(-2200 3900);
WIRE 16 -1 (-2200 3950)(-2200 3900);
WIRE 16 -1 (-1900 3950)(-2200 3950);
WIRE 16 -1 (-2200 4000)(-2200 3950);
WIRE 16 -1 (-1900 4000)(-2200 4000);
WIRE 16 -1 (-2200 4050)(-2200 4000);
WIRE 16 -1 (-2200 4100)(-2200 4050);
WIRE 16 -1 (-1900 4050)(-2200 4050);
WIRE 16 -1 (-1900 4100)(-2200 4100);
WIRE 16 -1 (-2200 4150)(-2200 4100);
WIRE 16 -1 (-1900 4150)(-2200 4150);
WIRE 16 -1 (-2200 4200)(-2200 4150);
WIRE 16 -1 (-1900 4200)(-2200 4200);
WIRE 16 -1 (-2200 4250)(-2200 4200);
WIRE 16 -1 (-1900 4250)(-2200 4250);
WIRE 16 -1 (-2200 4300)(-2200 4250);
WIRE 16 -1 (-1900 4300)(-2200 4300);
WIRE 16 -1 (-2200 4350)(-2200 4300);
WIRE 16 -1 (-1900 4350)(-2200 4350);
WIRE 16 -1 (-2200 4400)(-2200 4350);
WIRE 16 -1 (-1900 4400)(-2200 4400);
WIRE 16 -1 (-2200 4450)(-2200 4400);
WIRE 16 -1 (-1900 4450)(-2200 4450);
WIRE 16 -1 (-2200 4500)(-2200 4450);
WIRE 16 -1 (-1900 4500)(-2200 4500);
WIRE 16 -1 (-2200 4550)(-2200 4500);
WIRE 16 -1 (-1900 4550)(-2200 4550);
WIRE 16 -1 (-2200 4600)(-2200 4550);
WIRE 16 -1 (-1900 4600)(-2200 4600);
WIRE 16 -1 (-2200 4650)(-2200 4600);
WIRE 16 -1 (-1900 4650)(-2200 4650);
WIRE 16 -1 (-2200 4700)(-2200 4650);
WIRE 16 -1 (-1900 4700)(-2200 4700);
WIRE 16 -1 (-2200 4750)(-2200 4700);
WIRE 16 -1 (-1900 4750)(-2200 4750);
WIRE 16 -1 (-2200 4800)(-2200 4750);
WIRE 16 -1 (-1900 4800)(-2200 4800);
WIRE 16 -1 (-2200 4850)(-2200 4800);
WIRE 16 -1 (-1900 4850)(-2200 4850);
WIRE 16 -1 (-2200 4900)(-2200 4850);
WIRE 16 -1 (-1900 4900)(-2200 4900);
WIRE 16 -1 (-2200 4950)(-2200 4900);
WIRE 16 -1 (-1900 4950)(-2200 4950);
WIRE 16 -1 (-2200 5000)(-2200 4950);
WIRE 16 -1 (-1900 5000)(-2200 5000);
WIRE 16 -1 (-2200 5050)(-2200 5000);
WIRE 16 -1 (-1900 5050)(-2200 5050);
WIRE 16 -1 (-2200 5100)(-2200 5050);
WIRE 16 -1 (-1900 5100)(-2200 5100);
WIRE 16 -1 (-2200 5150)(-2200 5100);
WIRE 16 -1 (-1900 5150)(-2200 5150);
WIRE 16 -1 (-2200 5200)(-2200 5150);
WIRE 16 -1 (-1900 5200)(-2200 5200);
WIRE 16 -1 (-2200 5250)(-2200 5200);
WIRE 16 -1 (-1900 5250)(-2200 5250);
WIRE 16 -1 (-3675 3675)(-3525 3675);
WIRE 16 -1 (-3675 3625)(-3325 3625);
WIRE 16 -1 (-3675 4725)(-3525 4725);
WIRE 16 -1 (-3675 4675)(-3325 4675);
WIRE 16 -1 (-3525 4625)(-3675 4625);
WIRE 16 -1 (-3675 4575)(-3325 4575);
WIRE 16 -1 (-3675 3425)(-3325 3425);
WIRE 16 -1 (-3525 4525)(-3675 4525);
WIRE 16 -1 (-3525 3375)(-3675 3375);
WIRE 16 -1 (-3675 3325)(-3325 3325);
WIRE 16 -1 (-3325 4375)(-3675 4375);
WIRE 16 -1 (-3675 3275)(-3525 3275);
WIRE 16 -1 (-3675 3225)(-3325 3225);
WIRE 16 -1 (-3675 4325)(-3525 4325);
WIRE 16 -1 (-3675 4275)(-3325 4275);
WIRE 16 -1 (-3525 3175)(-3675 3175);
WIRE 16 -1 (-3675 3125)(-3325 3125);
WIRE 16 -1 (-3525 4225)(-3675 4225);
WIRE 16 -1 (-3325 4175)(-3675 4175);
WIRE 16 -1 (-3525 3075)(-3675 3075);
WIRE 16 -1 (-3675 3025)(-3325 3025);
WIRE 16 -1 (-3525 4125)(-3675 4125);
WIRE 16 -1 (-3675 4075)(-3325 4075);
WIRE 16 -1 (-3525 2975)(-3675 2975);
WIRE 16 -1 (-3675 2925)(-3325 2925);
WIRE 16 -1 (-3525 4025)(-3675 4025);
WIRE 16 -1 (-3675 3975)(-3325 3975);
WIRE 16 -1 (-3675 2875)(-3525 2875);
WIRE 16 -1 (-3675 2825)(-3325 2825);
WIRE 16 -1 (-3675 3925)(-3525 3925);
WIRE 16 -1 (-3675 3875)(-3325 3875);
WIRE 16 -1 (-3525 2775)(-3675 2775);
WIRE 16 -1 (-3675 2725)(-3325 2725);
WIRE 16 -1 (-3525 3825)(-3675 3825);
WIRE 16 -1 (-3675 3775)(-3325 3775);
WIRE 16 -1 (-3525 3475)(-3675 3475);
WIRE 16 -1 (-3675 3525)(-3325 3525);
WIRE 16 -1 (-3525 3575)(-3675 3575);
WIRE 16 -1 (-3525 4425)(-3675 4425);
WIRE 16 -1 (-3675 4475)(-3325 4475);
WIRE 16 -1 (-6350 5575)(-6150 5575);
WIRE 16 -1 (-7550 2425)(-8150 2425);
FORCEPROP 2 LAST SIG_NAME TP_CHD_CPU1_DIMM_RFU_2
J 0
(-8160 2435);
DISPLAY 0.489362 (-8160 2435);
FORCEPROP 2 LASTPROP $XRERR UNIQUE?
J 0
(-8390 2425);
DISPLAY 0.638298 (-8390 2425);
PAINT MONO (-8390 2425);
DISPLAY INVISIBLE (-8390 2425);
WIRE 16 -1 (-7550 2525)(-8150 2525);
FORCEPROP 2 LAST SIG_NAME TP_CHD_CPU1_DIMM_RFU_4
J 0
(-8160 2535);
DISPLAY 0.489362 (-8160 2535);
FORCEPROP 2 LASTPROP $XRERR UNIQUE?
J 0
(-8390 2525);
DISPLAY 0.638298 (-8390 2525);
PAINT MONO (-8390 2525);
DISPLAY INVISIBLE (-8390 2525);
WIRE 16 -1 (-7550 2575)(-8150 2575);
FORCEPROP 2 LAST SIG_NAME TP_CHD_CPU1_DIMM_RFU_5
J 0
(-8160 2585);
DISPLAY 0.489362 (-8160 2585);
FORCEPROP 2 LASTPROP $XRERR UNIQUE?
J 0
(-8390 2575);
DISPLAY 0.638298 (-8390 2575);
PAINT MONO (-8390 2575);
DISPLAY INVISIBLE (-8390 2575);
WIRE 16 -1 (-7550 3275)(-8200 3275);
FORCEPROP 2 LAST SIG_NAME M_D_CPU1_RESET_N
J 0
(-8185 3285);
DISPLAY 0.489362 (-8185 3285);
WIRE 16 -1 (-7550 4725)(-8350 4725);
FORCEPROP 2 LAST SIG_NAME M_D_CPU1_SB_PAR
J 0
(-8300 4735);
DISPLAY 0.489362 (-8300 4735);
WIRE 16 -1 (-7550 4775)(-8350 4775);
FORCEPROP 2 LAST SIG_NAME M_D_CPU1_SA_PAR
J 0
(-8300 4785);
DISPLAY 0.489362 (-8300 4785);
WIRE 16 -1 (-7550 2125)(-8350 2125);
FORCEPROP 2 LAST SIG_NAME M_D_CPU1_SB_RSP<0>
J 0
(-8300 2135);
DISPLAY 0.489362 (-8300 2135);
WIRE 16 -1 (-7550 2175)(-8350 2175);
FORCEPROP 2 LAST SIG_NAME M_D_CPU1_SA_RSP<0>
J 0
(-8300 2185);
DISPLAY 0.489362 (-8300 2185);
WIRE 16 -1 (-6150 2375)(-6350 2375);
WIRE 16 -1 (-6150 2425)(-6350 2425);
WIRE 16 -1 (-6150 2475)(-6350 2475);
WIRE 16 -1 (-6350 2525)(-6150 2525);
WIRE 16 -1 (-6150 2575)(-6350 2575);
WIRE 16 -1 (-6150 2625)(-6350 2625);
WIRE 16 -1 (-6150 2675)(-6350 2675);
WIRE 16 -1 (-6350 2725)(-6150 2725);
WIRE 16 -1 (-6150 2775)(-6350 2775);
WIRE 16 -1 (-6150 2825)(-6350 2825);
WIRE 16 -1 (-6150 2875)(-6350 2875);
WIRE 16 -1 (-6350 2925)(-6150 2925);
WIRE 16 -1 (-6150 2975)(-6350 2975);
WIRE 16 -1 (-6150 3025)(-6350 3025);
WIRE 16 -1 (-6150 3075)(-6350 3075);
WIRE 16 -1 (-6350 3125)(-6150 3125);
WIRE 16 -1 (-6150 3175)(-6350 3175);
WIRE 16 -1 (-6150 3225)(-6350 3225);
WIRE 16 -1 (-6150 3275)(-6350 3275);
WIRE 16 -1 (-6350 3325)(-6150 3325);
WIRE 16 -1 (-6150 3375)(-6350 3375);
WIRE 16 -1 (-6150 3425)(-6350 3425);
WIRE 16 -1 (-6150 3475)(-6350 3475);
WIRE 16 -1 (-6350 3525)(-6150 3525);
WIRE 16 -1 (-6150 3575)(-6350 3575);
WIRE 16 -1 (-6150 3625)(-6350 3625);
WIRE 16 -1 (-6150 3675)(-6350 3675);
WIRE 16 -1 (-6350 3725)(-6150 3725);
WIRE 16 -1 (-6150 3775)(-6350 3775);
WIRE 16 -1 (-6150 3825)(-6350 3825);
WIRE 16 -1 (-6150 3875)(-6350 3875);
WIRE 16 -1 (-6350 3925)(-6150 3925);
WIRE 16 -1 (-6150 4025)(-6350 4025);
WIRE 16 -1 (-6150 4075)(-6350 4075);
WIRE 16 -1 (-6150 4125)(-6350 4125);
WIRE 16 -1 (-6350 4175)(-6150 4175);
WIRE 16 -1 (-6150 4225)(-6350 4225);
WIRE 16 -1 (-6150 4275)(-6350 4275);
WIRE 16 -1 (-6150 4325)(-6350 4325);
WIRE 16 -1 (-6350 4375)(-6150 4375);
WIRE 16 -1 (-6150 4425)(-6350 4425);
WIRE 16 -1 (-6150 4475)(-6350 4475);
WIRE 16 -1 (-6150 4525)(-6350 4525);
WIRE 16 -1 (-6350 4575)(-6150 4575);
WIRE 16 -1 (-6150 4625)(-6350 4625);
WIRE 16 -1 (-6150 4675)(-6350 4675);
WIRE 16 -1 (-6150 4725)(-6350 4725);
WIRE 16 -1 (-6350 4775)(-6150 4775);
WIRE 16 -1 (-6150 4825)(-6350 4825);
WIRE 16 -1 (-6150 4875)(-6350 4875);
WIRE 16 -1 (-6150 4925)(-6350 4925);
WIRE 16 -1 (-6350 4975)(-6150 4975);
WIRE 16 -1 (-6150 5025)(-6350 5025);
WIRE 16 -1 (-6150 5075)(-6350 5075);
WIRE 16 -1 (-6150 5125)(-6350 5125);
WIRE 16 -1 (-6350 5175)(-6150 5175);
WIRE 16 -1 (-6150 5225)(-6350 5225);
WIRE 16 -1 (-6150 5275)(-6350 5275);
WIRE 16 -1 (-6150 5325)(-6350 5325);
WIRE 16 -1 (-6350 5375)(-6150 5375);
WIRE 16 -1 (-6150 5425)(-6350 5425);
WIRE 16 -1 (-6150 5475)(-6350 5475);
WIRE 16 -1 (-6150 5525)(-6350 5525);
WIRE 16 -1 (-7550 4475)(-8350 4475);
FORCEPROP 2 LAST SIG_NAME M_D_CPU1_SB_CS_N<1>
J 0
(-8300 4485);
DISPLAY 0.489362 (-8300 4485);
WIRE 16 -1 (-7550 4625)(-8350 4625);
FORCEPROP 2 LAST SIG_NAME M_D_CPU1_SA_CS_N<1>
J 0
(-8300 4635);
DISPLAY 0.489362 (-8300 4635);
WIRE 16 -1 (-7550 4425)(-8350 4425);
FORCEPROP 2 LAST SIG_NAME M_D_CPU1_SB_CS_N<0>
J 0
(-8300 4435);
DISPLAY 0.489362 (-8300 4435);
WIRE 16 -1 (-7550 4575)(-8350 4575);
FORCEPROP 2 LAST SIG_NAME M_D_CPU1_SA_CS_N<0>
J 0
(-8300 4585);
DISPLAY 0.489362 (-8300 4585);
WIRE 16 -1 (-7550 4325)(-8350 4325);
FORCEPROP 2 LAST SIG_NAME M_D_CPU1_CLK_DP<0>
J 0
(-8300 4335);
DISPLAY 0.489362 (-8300 4335);
WIRE 16 -1 (-7550 4275)(-8350 4275);
FORCEPROP 2 LAST SIG_NAME M_D_CPU1_CLK_DN<0>
J 0
(-8300 4285);
DISPLAY 0.489362 (-8300 4285);
WIRE 16 -1 (-7550 3375)(-7750 3375);
WIRE 16 -1 (-7550 3425)(-7750 3425);
WIRE 16 -1 (-7550 3475)(-7750 3475);
WIRE 16 -1 (-7550 3525)(-7750 3525);
WIRE 16 -1 (-7550 3575)(-7750 3575);
WIRE 16 -1 (-7550 3625)(-7750 3625);
WIRE 16 -1 (-7550 3675)(-7750 3675);
WIRE 16 -1 (-7550 3825)(-7750 3825);
WIRE 16 -1 (-7550 3925)(-7750 3925);
WIRE 16 -1 (-7550 3975)(-7750 3975);
WIRE 16 -1 (-7550 4075)(-7750 4075);
WIRE 16 -1 (-7550 4125)(-7750 4125);
WIRE 16 -1 (-7550 5175)(-7750 5175);
WIRE 16 -1 (-7550 5575)(-7750 5575);
WIRE 16 -1 (-7550 5125)(-7750 5125);
WIRE 16 -1 (-7550 5525)(-7750 5525);
WIRE 16 -1 (-7550 5075)(-7750 5075);
WIRE 16 -1 (-7550 5475)(-7750 5475);
WIRE 16 -1 (-7550 5025)(-7750 5025);
WIRE 16 -1 (-7550 5425)(-7750 5425);
WIRE 16 -1 (-7550 4975)(-7750 4975);
WIRE 16 -1 (-7550 5375)(-7750 5375);
WIRE 16 -1 (-7550 4925)(-7750 4925);
WIRE 16 -1 (-7550 5325)(-7750 5325);
WIRE 16 -1 (-7550 4875)(-7750 4875);
WIRE 16 -1 (-7550 5275)(-7750 5275);
WIRE 16 -1 (-7550 3225)(-8200 3225);
FORCEPROP 2 LAST SIG_NAME M_D_CPU1_ALERT_N
J 0
(-8185 3235);
DISPLAY 0.489362 (-8185 3235);
WIRE 16 -1 (-7550 3725)(-7750 3725);
WIRE 16 -1 (-7550 3875)(-7750 3875);
WIRE 16 -1 (-7550 4025)(-7750 4025);
WIRE 16 -1 (-7550 4175)(-7750 4175);
WIRE 16 -1 (-6525 1600)(-6525 1525);
WIRE 16 -1 (-6525 1600)(-7250 1600);
FORCEPROP 2 LAST SIG_NAME PD_CHD_CPU1_DIMM_SAA
J 0
(-7235 1610);
DISPLAY 0.489362 (-7235 1610);
DOT 1 (-2325 6000);
DOT 1 (-2900 6000);
DOT 1 (-2900 5575);
DOT 1 (-8650 3525);
DOT 1 (-2200 2150);
DOT 1 (-2200 2200);
DOT 1 (-2200 2250);
DOT 1 (-2200 2350);
DOT 1 (-2200 2300);
DOT 1 (-2200 2400);
DOT 1 (-2200 2450);
DOT 1 (-2200 2500);
DOT 1 (-2200 2600);
DOT 1 (-2200 2550);
DOT 1 (-2200 2650);
DOT 1 (-2200 2700);
DOT 1 (-2200 2750);
DOT 1 (-2200 2900);
DOT 1 (-2200 2850);
DOT 1 (-2200 2800);
DOT 1 (-2200 3000);
DOT 1 (-2200 2950);
DOT 1 (-2200 3050);
DOT 1 (-2200 3100);
DOT 1 (-2200 3150);
DOT 1 (-2200 3200);
DOT 1 (-2200 3250);
DOT 1 (-2200 3300);
DOT 1 (-2200 3350);
DOT 1 (-2200 3400);
DOT 1 (-2200 3500);
DOT 1 (-2200 3450);
DOT 1 (-2200 3550);
DOT 1 (-2200 3600);
DOT 1 (-2200 3650);
DOT 1 (-2200 3750);
DOT 1 (-2200 3700);
DOT 1 (-400 2050);
DOT 1 (-400 2100);
DOT 1 (-400 2250);
DOT 1 (-400 2150);
DOT 1 (-400 2350);
DOT 1 (-400 2300);
DOT 1 (-400 2400);
DOT 1 (-400 2450);
DOT 1 (-400 2500);
DOT 1 (-400 2600);
DOT 1 (-400 2550);
DOT 1 (-400 2650);
DOT 1 (-400 2700);
DOT 1 (-400 2750);
DOT 1 (-400 2800);
DOT 1 (-400 2900);
DOT 1 (-400 2850);
DOT 1 (-400 2950);
DOT 1 (-400 3000);
DOT 1 (-400 3050);
DOT 1 (-400 3100);
DOT 1 (-400 3150);
DOT 1 (-400 3200);
DOT 1 (-400 3250);
DOT 1 (-400 3300);
DOT 1 (-400 3350);
DOT 1 (-400 3400);
DOT 1 (-400 3500);
DOT 1 (-400 3450);
DOT 1 (-400 3550);
DOT 1 (-400 3600);
DOT 1 (-400 3650);
DOT 1 (-400 3750);
DOT 1 (-400 3700);
DOT 1 (-400 3800);
DOT 1 (-2200 3800);
DOT 1 (-2200 3850);
DOT 1 (-2200 3900);
DOT 1 (-2200 3950);
DOT 1 (-2200 4000);
DOT 1 (-2200 4050);
DOT 1 (-2200 4150);
DOT 1 (-2200 4100);
DOT 1 (-2200 4200);
DOT 1 (-2200 4250);
DOT 1 (-2200 4300);
DOT 1 (-2200 4400);
DOT 1 (-2200 4350);
DOT 1 (-2200 4500);
DOT 1 (-2200 4450);
DOT 1 (-2200 4550);
DOT 1 (-2200 4650);
DOT 1 (-2200 4600);
DOT 1 (-2200 4700);
DOT 1 (-2200 4750);
DOT 1 (-2200 4800);
DOT 1 (-2200 4900);
DOT 1 (-2200 4850);
DOT 1 (-2200 4950);
DOT 1 (-2200 5000);
DOT 1 (-2200 5050);
DOT 1 (-2200 5150);
DOT 1 (-2200 5200);
DOT 1 (-2200 5350);
DOT 1 (-2200 5400);
DOT 1 (-400 3850);
DOT 1 (-400 3900);
DOT 1 (-400 3950);
DOT 1 (-400 4000);
DOT 1 (-400 4050);
DOT 1 (-400 4100);
DOT 1 (-400 4150);
DOT 1 (-400 4200);
DOT 1 (-400 4250);
DOT 1 (-400 4300);
DOT 1 (-400 4400);
DOT 1 (-400 4350);
DOT 1 (-400 4500);
DOT 1 (-400 4450);
DOT 1 (-400 4550);
DOT 1 (-400 4650);
DOT 1 (-400 4600);
DOT 1 (-400 4700);
DOT 1 (-400 4750);
DOT 1 (-400 4800);
DOT 1 (-400 4900);
DOT 1 (-400 4850);
DOT 1 (-400 4950);
DOT 1 (-400 5000);
DOT 1 (-400 5050);
DOT 1 (-400 5100);
DOT 1 (-400 5150);
DOT 1 (-400 5200);
DOT 1 (-400 5300);
DOT 1 (-400 5250);
DOT 1 (-400 5350);
DOT 1 (-2200 5100);
DOT 1 (-8475 2325);
QUIT
